FILE_TYPE = MACRO_DRAWING;
SET COLOR_WIRE YELLOW;
SET COLOR_PROP ORANGE;
SET COLOR_DOT WHITE;
SET COLOR_ARC YELLOW;
SET COLOR_BODY GREEN;
SET COLOR_NOTE PURPLE;
SET PROP_DISPLAY VALUE;
SET PAGE_NUMBER P20;
SET PATH_NUMBER P200;
FORCEADD OFFPAGE..2
R 2
(-3250 -850);
FORCEPROP 2 LAST $XR0 20 
J 0
(-3474 -850);
DISPLAY 0.638298 (-3474 -850);
PAINT MONO (-3474 -850);
FORCEPROP 2 LAST PATH I1
J 0
(-3450 -800);
DISPLAY 1.021277 (-3450 -800);
DISPLAY INVISIBLE (-3450 -800);
FORCEPROP 1 LAST COMMENT_BODY TRUE
J 2
(-3205 -945);
DISPLAY 0.872340 (-3205 -945);
PAINT PEACH (-3205 -945);
DISPLAY INVISIBLE (-3205 -945);
FORCEPROP 1 LAST OFFPAGE TRUE
J 2
(-3575 -975);
DISPLAY 0.872340 (-3575 -975);
PAINT GREEN (-3575 -975);
DISPLAY INVISIBLE (-3575 -975);
FORCEPROP 2 LAST CDS_LIB standard
J 0
(-3250 -850);
DISPLAY INVISIBLE (-3250 -850);
FORCEADD OFFPAGE..1
(-2950 3850);
FORCEPROP 2 LAST $XR1 20 
J 0
(-3291 3850);
DISPLAY 0.638298 (-3291 3850);
PAINT MONO (-3291 3850);
FORCEPROP 2 LAST $XR0 12 
J 0
(-3201 3850);
DISPLAY 0.638298 (-3201 3850);
PAINT MONO (-3201 3850);
FORCEPROP 2 LAST PATH I10
J 0
(-3150 3900);
DISPLAY 1.021277 (-3150 3900);
DISPLAY INVISIBLE (-3150 3900);
FORCEPROP 1 LAST COMMENT_BODY TRUE
J 0
(-2825 3750);
DISPLAY 0.872340 (-2825 3750);
PAINT PEACH (-2825 3750);
DISPLAY INVISIBLE (-2825 3750);
FORCEPROP 1 LAST OFFPAGE TRUE
J 0
(-2625 3725);
DISPLAY 0.872340 (-2625 3725);
PAINT GREEN (-2625 3725);
DISPLAY INVISIBLE (-2625 3725);
FORCEPROP 2 LAST CDS_LIB standard
J 0
(-2950 3850);
DISPLAY INVISIBLE (-2950 3850);
FORCEADD OFFPAGE..2
R 2
(2375 1275);
FORCEPROP 2 LAST $XR1 20 
J 0
(2061 1275);
DISPLAY 0.638298 (2061 1275);
PAINT MONO (2061 1275);
FORCEPROP 2 LAST $XR0 12 
J 0
(2151 1275);
DISPLAY 0.638298 (2151 1275);
PAINT MONO (2151 1275);
FORCEPROP 2 LAST PATH I100
J 0
(2200 1325);
DISPLAY 1.021277 (2200 1325);
DISPLAY INVISIBLE (2200 1325);
FORCEPROP 1 LAST COMMENT_BODY TRUE
J 2
(2420 1180);
DISPLAY 0.872340 (2420 1180);
PAINT PEACH (2420 1180);
DISPLAY INVISIBLE (2420 1180);
FORCEPROP 1 LAST OFFPAGE TRUE
J 2
(2050 1150);
DISPLAY 0.872340 (2050 1150);
PAINT GREEN (2050 1150);
DISPLAY INVISIBLE (2050 1150);
FORCEPROP 2 LAST CDS_LIB standard
J 0
(2375 1275);
DISPLAY INVISIBLE (2375 1275);
FORCEADD OFFPAGE..2
R 2
(2375 1425);
FORCEPROP 2 LAST $XR1 20 
J 0
(2061 1425);
DISPLAY 0.638298 (2061 1425);
PAINT MONO (2061 1425);
FORCEPROP 2 LAST $XR0 12 
J 0
(2151 1425);
DISPLAY 0.638298 (2151 1425);
PAINT MONO (2151 1425);
FORCEPROP 2 LAST PATH I101
J 0
(2200 1475);
DISPLAY 1.021277 (2200 1475);
DISPLAY INVISIBLE (2200 1475);
FORCEPROP 1 LAST COMMENT_BODY TRUE
J 2
(2420 1330);
DISPLAY 0.872340 (2420 1330);
PAINT PEACH (2420 1330);
DISPLAY INVISIBLE (2420 1330);
FORCEPROP 1 LAST OFFPAGE TRUE
J 2
(2050 1300);
DISPLAY 0.872340 (2050 1300);
PAINT GREEN (2050 1300);
DISPLAY INVISIBLE (2050 1300);
FORCEPROP 2 LAST CDS_LIB standard
J 0
(2375 1425);
DISPLAY INVISIBLE (2375 1425);
FORCEADD OFFPAGE..2
R 2
(2375 1575);
FORCEPROP 2 LAST $XR1 20 
J 0
(2061 1575);
DISPLAY 0.638298 (2061 1575);
PAINT MONO (2061 1575);
FORCEPROP 2 LAST $XR0 12 
J 0
(2151 1575);
DISPLAY 0.638298 (2151 1575);
PAINT MONO (2151 1575);
FORCEPROP 2 LAST PATH I102
J 0
(2200 1625);
DISPLAY 1.021277 (2200 1625);
DISPLAY INVISIBLE (2200 1625);
FORCEPROP 1 LAST COMMENT_BODY TRUE
J 2
(2420 1480);
DISPLAY 0.872340 (2420 1480);
PAINT PEACH (2420 1480);
DISPLAY INVISIBLE (2420 1480);
FORCEPROP 1 LAST OFFPAGE TRUE
J 2
(2050 1450);
DISPLAY 0.872340 (2050 1450);
PAINT GREEN (2050 1450);
DISPLAY INVISIBLE (2050 1450);
FORCEPROP 2 LAST CDS_LIB standard
J 0
(2375 1575);
DISPLAY INVISIBLE (2375 1575);
FORCEADD OFFPAGE..2
R 2
(2375 1725);
FORCEPROP 2 LAST $XR1 20 
J 0
(2061 1725);
DISPLAY 0.638298 (2061 1725);
PAINT MONO (2061 1725);
FORCEPROP 2 LAST $XR0 12 
J 0
(2151 1725);
DISPLAY 0.638298 (2151 1725);
PAINT MONO (2151 1725);
FORCEPROP 2 LAST PATH I103
J 0
(2200 1775);
DISPLAY 1.021277 (2200 1775);
DISPLAY INVISIBLE (2200 1775);
FORCEPROP 1 LAST COMMENT_BODY TRUE
J 2
(2420 1630);
DISPLAY 0.872340 (2420 1630);
PAINT PEACH (2420 1630);
DISPLAY INVISIBLE (2420 1630);
FORCEPROP 1 LAST OFFPAGE TRUE
J 2
(2050 1600);
DISPLAY 0.872340 (2050 1600);
PAINT GREEN (2050 1600);
DISPLAY INVISIBLE (2050 1600);
FORCEPROP 2 LAST CDS_LIB standard
J 0
(2375 1725);
DISPLAY INVISIBLE (2375 1725);
FORCEADD OFFPAGE..2
R 2
(2375 1875);
FORCEPROP 2 LAST $XR1 20 
J 0
(2061 1875);
DISPLAY 0.638298 (2061 1875);
PAINT MONO (2061 1875);
FORCEPROP 2 LAST $XR0 12 
J 0
(2151 1875);
DISPLAY 0.638298 (2151 1875);
PAINT MONO (2151 1875);
FORCEPROP 2 LAST PATH I104
J 0
(2200 1925);
DISPLAY 1.021277 (2200 1925);
DISPLAY INVISIBLE (2200 1925);
FORCEPROP 1 LAST COMMENT_BODY TRUE
J 2
(2420 1780);
DISPLAY 0.872340 (2420 1780);
PAINT PEACH (2420 1780);
DISPLAY INVISIBLE (2420 1780);
FORCEPROP 1 LAST OFFPAGE TRUE
J 2
(2050 1750);
DISPLAY 0.872340 (2050 1750);
PAINT GREEN (2050 1750);
DISPLAY INVISIBLE (2050 1750);
FORCEPROP 2 LAST CDS_LIB standard
J 0
(2375 1875);
DISPLAY INVISIBLE (2375 1875);
FORCEADD OFFPAGE..2
R 2
(2375 2025);
FORCEPROP 2 LAST $XR1 20 
J 0
(2061 2025);
DISPLAY 0.638298 (2061 2025);
PAINT MONO (2061 2025);
FORCEPROP 2 LAST $XR0 12 
J 0
(2151 2025);
DISPLAY 0.638298 (2151 2025);
PAINT MONO (2151 2025);
FORCEPROP 2 LASTPIN (2425 2025) SIG_NAME M_BMC_DDR4_MWE_N
J 0
(2465 2035);
DISPLAY 0.808511 (2465 2035);
FORCEPROP 2 LAST PATH I105
J 0
(2200 2075);
DISPLAY 1.021277 (2200 2075);
DISPLAY INVISIBLE (2200 2075);
FORCEPROP 1 LAST COMMENT_BODY TRUE
J 2
(2420 1930);
DISPLAY 0.872340 (2420 1930);
PAINT PEACH (2420 1930);
DISPLAY INVISIBLE (2420 1930);
FORCEPROP 1 LAST OFFPAGE TRUE
J 2
(2050 1900);
DISPLAY 0.872340 (2050 1900);
PAINT GREEN (2050 1900);
DISPLAY INVISIBLE (2050 1900);
FORCEPROP 2 LAST CDS_LIB standard
J 0
(2375 2025);
DISPLAY INVISIBLE (2375 2025);
FORCEADD Q_CAP..2
(3700 -1050);
FORCEPROP 1 LAST VALUE 0.22UF
J 2
(4100 -1050);
DISPLAY 0.510638 (4100 -1050);
PAINT SKYBLUE (4100 -1050);
FORCEPROP 1 LAST PATH I106
J 0
(3700 -850);
DISPLAY 0.978723 (3700 -850);
PAINT WHITE (3700 -850);
DISPLAY INVISIBLE (3700 -850);
FORCEPROP 1 LAST PACK_TYPE 0402
J 1
(3700 -1250);
DISPLAY 0.510638 (3700 -1250);
PAINT SKYBLUE (3700 -1250);
DISPLAY INVISIBLE (3700 -1250);
FORCEPROP 2 LAST SEC_TYPE 0402
J 0
(3700 -800);
DISPLAY 0.680851 (3700 -800);
DISPLAY INVISIBLE (3700 -800);
FORCEPROP 2 LAST CDS_LIB pure_quanta
J 0
(3700 -1050);
DISPLAY INVISIBLE (3700 -1050);
FORCEPROP 1 LAST VOLTAGE 16V
J 0
(3700 -1150);
DISPLAY 0.510638 (3700 -1150);
PAINT SKYBLUE (3700 -1150);
DISPLAY INVISIBLE (3700 -1150);
FORCEPROP 1 LAST TOLERANCE 10%
J 2
(3700 -1200);
DISPLAY 0.510638 (3700 -1200);
PAINT SKYBLUE (3700 -1200);
DISPLAY INVISIBLE (3700 -1200);
FORCEPROP 1 LAST PART_NUMBER CH4223K1B00
J 1
(3700 -1000);
DISPLAY 0.510638 (3700 -1000);
PAINT WHITE (3700 -1000);
DISPLAY INVISIBLE (3700 -1000);
FORCEPROP 1 LAST MATERIAL X7R
J 0
(3700 -1200);
DISPLAY 0.510638 (3700 -1200);
PAINT SKYBLUE (3700 -1200);
DISPLAY INVISIBLE (3700 -1200);
FORCEPROP 1 LAST LOCATION C12
J 1
(3500 -1050);
DISPLAY 0.702128 (3500 -1050);
PAINT YELLOW (3500 -1050);
FORCEPROP 1 LASTPIN (3600 -1050) $PN 1
J 0
(3590 -1035);
DISPLAY 0.808511 (3590 -1035);
PAINT WHITE (3590 -1035);
FORCEPROP 1 LASTPIN (3800 -1050) $PN 2
J 0
(3785 -1035);
DISPLAY 0.808511 (3785 -1035);
PAINT WHITE (3785 -1035);
FORCEPROP 2 LAST SEC 1
J 0
(3700 -800);
DISPLAY 0.680851 (3700 -800);
PAINT MONO (3700 -800);
DISPLAY INVISIBLE (3700 -800);
FORCEADD Q_CAP..2
(3700 -750);
FORCEPROP 1 LAST PART_NUMBER CH4223K1B00
J 1
(3900 -575);
DISPLAY 0.510638 (3900 -575);
PAINT WHITE (3900 -575);
FORCEPROP 1 LAST VALUE 0.22UF
J 2
(4150 -750);
DISPLAY 0.510638 (4150 -750);
PAINT SKYBLUE (4150 -750);
FORCEPROP 1 LAST MATERIAL EMPTY
J 0
(3875 -750);
DISPLAY 0.510638 (3875 -750);
PAINT RED (3875 -750);
FORCEPROP 1 LAST PATH I107
J 0
(3700 -550);
DISPLAY 0.978723 (3700 -550);
PAINT WHITE (3700 -550);
DISPLAY INVISIBLE (3700 -550);
FORCEPROP 1 LAST PACK_TYPE 0402
J 1
(3700 -950);
DISPLAY 0.510638 (3700 -950);
PAINT SKYBLUE (3700 -950);
DISPLAY INVISIBLE (3700 -950);
FORCEPROP 2 LAST CDS_LIB pure_quanta
J 0
(3700 -750);
DISPLAY INVISIBLE (3700 -750);
FORCEPROP 2 LAST SEC_TYPE 0402
J 0
(3700 -500);
DISPLAY 0.680851 (3700 -500);
DISPLAY INVISIBLE (3700 -500);
FORCEPROP 1 LAST VOLTAGE 16V
J 0
(3700 -850);
DISPLAY 0.510638 (3700 -850);
PAINT SKYBLUE (3700 -850);
DISPLAY INVISIBLE (3700 -850);
FORCEPROP 1 LAST TOLERANCE 10%
J 2
(3700 -900);
DISPLAY 0.510638 (3700 -900);
PAINT SKYBLUE (3700 -900);
DISPLAY INVISIBLE (3700 -900);
FORCEPROP 1 LAST LOCATION C229
J 1
(3500 -750);
DISPLAY 0.702128 (3500 -750);
PAINT YELLOW (3500 -750);
FORCEPROP 1 LASTPIN (3600 -750) $PN 1
J 0
(3590 -735);
DISPLAY 0.808511 (3590 -735);
PAINT WHITE (3590 -735);
FORCEPROP 1 LASTPIN (3800 -750) $PN 2
J 0
(3785 -735);
DISPLAY 0.808511 (3785 -735);
PAINT WHITE (3785 -735);
FORCEPROP 2 LAST SEC 1
J 0
(3700 -500);
DISPLAY 0.680851 (3700 -500);
PAINT MONO (3700 -500);
DISPLAY INVISIBLE (3700 -500);
FORCEADD UNIVERSAL_GND..1
(4000 -1300);
FORCEPROP 3 LASTPIN (4000 -1250) SIG_NAME GND\g
J 0
(4010 -1240);
DISPLAY 0.659574 (4010 -1240);
PAINT MONO (4010 -1240);
DISPLAY INVISIBLE (4010 -1240);
FORCEPROP 1 LAST PATH I108
J 0
(4075 -1300);
DISPLAY 0.872340 (4075 -1300);
PAINT AQUA (4075 -1300);
DISPLAY INVISIBLE (4075 -1300);
FORCEPROP 1 LAST HDL_POWER GND
J 1
(4025 -1375);
DISPLAY 0.702128 (4025 -1375);
PAINT GREEN (4025 -1375);
DISPLAY INVISIBLE (4025 -1375);
FORCEPROP 2 LAST CDS_LIB logical_power
J 0
(4000 -1300);
DISPLAY INVISIBLE (4000 -1300);
FORCEADD UNIVERSAL_GND..1
(3275 -50);
FORCEPROP 3 LASTPIN (3275 0) SIG_NAME GND\g
J 0
(3285 10);
DISPLAY 0.659574 (3285 10);
PAINT MONO (3285 10);
DISPLAY INVISIBLE (3285 10);
FORCEPROP 1 LAST PATH I109
J 0
(3350 -50);
DISPLAY 0.872340 (3350 -50);
PAINT AQUA (3350 -50);
DISPLAY INVISIBLE (3350 -50);
FORCEPROP 1 LAST HDL_POWER GND
J 1
(3300 -125);
DISPLAY 0.702128 (3300 -125);
PAINT GREEN (3300 -125);
DISPLAY INVISIBLE (3300 -125);
FORCEPROP 2 LAST CDS_LIB logical_power
J 0
(3275 -50);
DISPLAY INVISIBLE (3275 -50);
FORCEADD OFFPAGE..1
(-2950 3900);
FORCEPROP 2 LAST $XR1 20 
J 0
(-3291 3900);
DISPLAY 0.638298 (-3291 3900);
PAINT MONO (-3291 3900);
FORCEPROP 2 LAST $XR0 12 
J 0
(-3201 3900);
DISPLAY 0.638298 (-3201 3900);
PAINT MONO (-3201 3900);
FORCEPROP 2 LAST PATH I11
J 0
(-3150 3950);
DISPLAY 1.021277 (-3150 3950);
DISPLAY INVISIBLE (-3150 3950);
FORCEPROP 1 LAST COMMENT_BODY TRUE
J 0
(-2825 3800);
DISPLAY 0.872340 (-2825 3800);
PAINT PEACH (-2825 3800);
DISPLAY INVISIBLE (-2825 3800);
FORCEPROP 1 LAST OFFPAGE TRUE
J 0
(-2625 3775);
DISPLAY 0.872340 (-2625 3775);
PAINT GREEN (-2625 3775);
DISPLAY INVISIBLE (-2625 3775);
FORCEPROP 2 LAST CDS_LIB standard
J 0
(-2950 3900);
DISPLAY INVISIBLE (-2950 3900);
FORCEADD UNIVERSAL_POWER..1
(4175 -475);
FORCEPROP 3 LASTPIN (4175 -525) SIG_NAME P1V2_AUX\g
J 0
(4185 -515);
DISPLAY 0.659574 (4185 -515);
PAINT MONO (4185 -515);
DISPLAY INVISIBLE (4185 -515);
FORCEPROP 1 LAST HDL_POWER P1V2_AUX
J 1
(4175 -425);
DISPLAY 0.702128 (4175 -425);
PAINT GREEN (4175 -425);
FORCEPROP 1 LAST PATH I110
J 0
(4225 -450);
DISPLAY 0.872340 (4225 -450);
PAINT AQUA (4225 -450);
DISPLAY INVISIBLE (4225 -450);
FORCEPROP 2 LAST CDS_LIB logical_power
J 0
(4175 -475);
DISPLAY INVISIBLE (4175 -475);
FORCEADD Q_RES..1
(4325 175);
FORCEPROP 1 LAST PART_NUMBER CS24702FB06
J 0
(4075 75);
DISPLAY 0.510638 (4075 75);
PAINT WHITE (4075 75);
FORCEPROP 1 LAST PACK_TYPE 0402LF
J 0
(4050 25);
DISPLAY 0.510638 (4050 25);
PAINT SKYBLUE (4050 25);
FORCEPROP 1 LAST MATERIAL CHIP
J 0
(4225 25);
DISPLAY 0.510638 (4225 25);
PAINT SKYBLUE (4225 25);
FORCEPROP 1 LAST WATTAGE 1/16W
J 2
(4475 25);
DISPLAY 0.510638 (4475 25);
PAINT SKYBLUE (4475 25);
FORCEPROP 1 LAST TOLERANCE 1%
J 0
(4525 25);
DISPLAY 0.510638 (4525 25);
PAINT SKYBLUE (4525 25);
FORCEPROP 1 LAST VALUE 4.7K
J 2
(4625 175);
DISPLAY 0.510638 (4625 175);
PAINT SKYBLUE (4625 175);
FORCEPROP 1 LAST PATH I111
J 0
(4275 325);
DISPLAY 0.978723 (4275 325);
PAINT WHITE (4275 325);
DISPLAY INVISIBLE (4275 325);
FORCEPROP 2 LAST SEC_TYPE 0402LF
J 0
(4275 375);
DISPLAY 0.680851 (4275 375);
DISPLAY INVISIBLE (4275 375);
FORCEPROP 2 LAST CDS_LIB pure_quanta
J 0
(4325 175);
DISPLAY INVISIBLE (4325 175);
FORCEPROP 1 LAST LOCATION R9
J 0
(4100 200);
DISPLAY 0.702128 (4100 200);
PAINT YELLOW (4100 200);
FORCEPROP 1 LASTPIN (4225 175) $PN 1
J 0
(4237 187);
DISPLAY 0.808511 (4237 187);
PAINT WHITE (4237 187);
FORCEPROP 1 LASTPIN (4425 175) $PN 2
J 0
(4387 187);
DISPLAY 0.808511 (4387 187);
PAINT WHITE (4387 187);
FORCEPROP 2 LAST SEC 1
J 0
(4275 375);
DISPLAY 0.680851 (4275 375);
PAINT MONO (4275 375);
DISPLAY INVISIBLE (4275 375);
FORCEADD UNIVERSAL_GND..1
(4975 100);
FORCEPROP 3 LASTPIN (4975 150) SIG_NAME GND\g
J 0
(4985 160);
DISPLAY 0.659574 (4985 160);
PAINT MONO (4985 160);
DISPLAY INVISIBLE (4985 160);
FORCEPROP 1 LAST PATH I112
J 0
(5050 100);
DISPLAY 0.872340 (5050 100);
PAINT AQUA (5050 100);
DISPLAY INVISIBLE (5050 100);
FORCEPROP 1 LAST HDL_POWER GND
J 1
(5000 25);
DISPLAY 0.702128 (5000 25);
PAINT GREEN (5000 25);
DISPLAY INVISIBLE (5000 25);
FORCEPROP 2 LAST CDS_LIB logical_power
J 0
(4975 100);
DISPLAY INVISIBLE (4975 100);
FORCEADD Q_CAP..1
(4975 325);
FORCEPROP 1 LAST VOLTAGE 6.3V
J 0
(5025 325);
DISPLAY 0.510638 (5025 325);
PAINT SKYBLUE (5025 325);
FORCEPROP 1 LAST PACK_TYPE C0402
J 0
(5025 175);
DISPLAY 0.510638 (5025 175);
PAINT SKYBLUE (5025 175);
FORCEPROP 1 LAST TOLERANCE 20%
J 0
(5025 275);
DISPLAY 0.510638 (5025 275);
PAINT SKYBLUE (5025 275);
FORCEPROP 1 LAST VALUE 10UF
J 0
(5025 375);
DISPLAY 0.510638 (5025 375);
PAINT SKYBLUE (5025 375);
FORCEPROP 1 LAST PART_NUMBER CH6101MEB01
J 0
(5025 125);
DISPLAY 0.510638 (5025 125);
PAINT WHITE (5025 125);
FORCEPROP 1 LAST MATERIAL X6S
J 0
(5025 225);
DISPLAY 0.510638 (5025 225);
PAINT SKYBLUE (5025 225);
FORCEPROP 1 LAST PATH I113
J 0
(5025 475);
DISPLAY 0.978723 (5025 475);
PAINT WHITE (5025 475);
DISPLAY INVISIBLE (5025 475);
FORCEPROP 2 LAST SEC_TYPE C0402
J 0
(5025 525);
DISPLAY 0.680851 (5025 525);
DISPLAY INVISIBLE (5025 525);
FORCEPROP 2 LAST CDS_LIB pure_quanta
J 0
(4975 325);
DISPLAY INVISIBLE (4975 325);
FORCEPROP 1 LAST LOCATION C16
J 0
(5025 425);
DISPLAY 0.702128 (5025 425);
PAINT YELLOW (5025 425);
FORCEPROP 1 LASTPIN (4975 425) $PN 1
J 0
(4985 405);
DISPLAY 0.808511 (4985 405);
PAINT WHITE (4985 405);
FORCEPROP 1 LASTPIN (4975 225) $PN 2
J 0
(4985 205);
DISPLAY 0.808511 (4985 205);
PAINT WHITE (4985 205);
FORCEPROP 2 LAST SEC 1
J 0
(5025 525);
DISPLAY 0.680851 (5025 525);
PAINT MONO (5025 525);
DISPLAY INVISIBLE (5025 525);
FORCEADD Q_RES..1
(3650 425);
FORCEPROP 1 LAST MATERIAL EMPTY
J 0
(3800 425);
DISPLAY 0.510638 (3800 425);
PAINT RED (3800 425);
FORCEPROP 1 LAST VALUE 120
J 2
(4000 425);
DISPLAY 0.510638 (4000 425);
PAINT SKYBLUE (4000 425);
FORCEPROP 1 LAST PART_NUMBER CS11202FB02
J 0
(3600 525);
DISPLAY 0.510638 (3600 525);
PAINT WHITE (3600 525);
DISPLAY INVISIBLE (3600 525);
FORCEPROP 1 LAST PACK_TYPE 0402LF
J 0
(3900 275);
DISPLAY 0.510638 (3900 275);
PAINT SKYBLUE (3900 275);
DISPLAY INVISIBLE (3900 275);
FORCEPROP 1 LAST WATTAGE 1/16W
J 2
(3625 275);
DISPLAY 0.510638 (3625 275);
PAINT SKYBLUE (3625 275);
DISPLAY INVISIBLE (3625 275);
FORCEPROP 1 LAST PATH I114
J 0
(3600 575);
DISPLAY 0.978723 (3600 575);
PAINT WHITE (3600 575);
DISPLAY INVISIBLE (3600 575);
FORCEPROP 1 LAST TOLERANCE 1%
J 0
(3650 325);
DISPLAY 0.510638 (3650 325);
PAINT SKYBLUE (3650 325);
DISPLAY INVISIBLE (3650 325);
FORCEPROP 2 LAST CDS_LIB pure_quanta
J 0
(3650 425);
DISPLAY INVISIBLE (3650 425);
FORCEPROP 1 LAST LOCATION R350
J 0
(3375 425);
DISPLAY 0.702128 (3375 425);
PAINT YELLOW (3375 425);
FORCEPROP 1 LASTPIN (3550 425) $PN 1
J 0
(3562 437);
DISPLAY 0.808511 (3562 437);
PAINT WHITE (3562 437);
FORCEPROP 1 LASTPIN (3750 425) $PN 2
J 0
(3712 437);
DISPLAY 0.808511 (3712 437);
PAINT WHITE (3712 437);
FORCEPROP 0 LAST $SEC 1
J 0
(3950 475);
DISPLAY 0.680851 (3950 475);
PAINT MONO (3950 475);
DISPLAY INVISIBLE (3950 475);
FORCEPROP 0 LAST CDS_SEC 1
J 0
(3950 475);
DISPLAY 1.021277 (3950 475);
DISPLAY INVISIBLE (3950 475);
FORCEADD Q_RES..1
(4325 425);
FORCEPROP 1 LAST MATERIAL EMPTY
J 0
(4475 425);
DISPLAY 0.510638 (4475 425);
PAINT RED (4475 425);
FORCEPROP 1 LAST VALUE 120
J 2
(4675 425);
DISPLAY 0.510638 (4675 425);
PAINT SKYBLUE (4675 425);
FORCEPROP 1 LAST PART_NUMBER CS11202FB02
J 0
(4275 525);
DISPLAY 0.510638 (4275 525);
PAINT WHITE (4275 525);
DISPLAY INVISIBLE (4275 525);
FORCEPROP 1 LAST PACK_TYPE 0402LF
J 0
(4575 275);
DISPLAY 0.510638 (4575 275);
PAINT SKYBLUE (4575 275);
DISPLAY INVISIBLE (4575 275);
FORCEPROP 1 LAST WATTAGE 1/16W
J 2
(4300 275);
DISPLAY 0.510638 (4300 275);
PAINT SKYBLUE (4300 275);
DISPLAY INVISIBLE (4300 275);
FORCEPROP 1 LAST PATH I115
J 0
(4275 575);
DISPLAY 0.978723 (4275 575);
PAINT WHITE (4275 575);
DISPLAY INVISIBLE (4275 575);
FORCEPROP 1 LAST TOLERANCE 1%
J 0
(4325 325);
DISPLAY 0.510638 (4325 325);
PAINT SKYBLUE (4325 325);
DISPLAY INVISIBLE (4325 325);
FORCEPROP 2 LAST CDS_LIB pure_quanta
J 0
(4325 425);
DISPLAY INVISIBLE (4325 425);
FORCEPROP 1 LAST LOCATION R375
J 0
(4075 425);
DISPLAY 0.702128 (4075 425);
PAINT YELLOW (4075 425);
FORCEPROP 1 LASTPIN (4225 425) $PN 1
J 0
(4237 437);
DISPLAY 0.808511 (4237 437);
PAINT WHITE (4237 437);
FORCEPROP 1 LASTPIN (4425 425) $PN 2
J 0
(4387 437);
DISPLAY 0.808511 (4387 437);
PAINT WHITE (4387 437);
FORCEPROP 0 LAST $SEC 1
J 0
(4650 475);
DISPLAY 0.680851 (4650 475);
PAINT MONO (4650 475);
DISPLAY INVISIBLE (4650 475);
FORCEPROP 0 LAST CDS_SEC 1
J 0
(4650 475);
DISPLAY 1.021277 (4650 475);
DISPLAY INVISIBLE (4650 475);
FORCEADD Q_RES..1
(3650 575);
FORCEPROP 1 LAST VALUE 120
J 2
(4000 575);
DISPLAY 0.510638 (4000 575);
PAINT SKYBLUE (4000 575);
FORCEPROP 1 LAST MATERIAL CHIP
J 0
(3800 575);
DISPLAY 0.510638 (3800 575);
PAINT SKYBLUE (3800 575);
FORCEPROP 1 LAST PART_NUMBER CS11202FB02
J 0
(4325 750);
DISPLAY 0.510638 (4325 750);
PAINT WHITE (4325 750);
DISPLAY INVISIBLE (4325 750);
FORCEPROP 1 LAST PACK_TYPE 0402LF
J 0
(3900 425);
DISPLAY 0.510638 (3900 425);
PAINT SKYBLUE (3900 425);
DISPLAY INVISIBLE (3900 425);
FORCEPROP 1 LAST WATTAGE 1/16W
J 2
(3625 425);
DISPLAY 0.510638 (3625 425);
PAINT SKYBLUE (3625 425);
DISPLAY INVISIBLE (3625 425);
FORCEPROP 1 LAST PATH I116
J 0
(3600 725);
DISPLAY 0.978723 (3600 725);
PAINT WHITE (3600 725);
DISPLAY INVISIBLE (3600 725);
FORCEPROP 1 LAST TOLERANCE 1%
J 0
(3650 475);
DISPLAY 0.510638 (3650 475);
PAINT SKYBLUE (3650 475);
DISPLAY INVISIBLE (3650 475);
FORCEPROP 2 LAST CDS_LIB pure_quanta
J 0
(3650 575);
DISPLAY INVISIBLE (3650 575);
FORCEPROP 1 LAST LOCATION R349
J 0
(3375 575);
DISPLAY 0.702128 (3375 575);
PAINT YELLOW (3375 575);
FORCEPROP 1 LASTPIN (3550 575) $PN 1
J 0
(3562 587);
DISPLAY 0.808511 (3562 587);
PAINT WHITE (3562 587);
FORCEPROP 1 LASTPIN (3750 575) $PN 2
J 0
(3712 587);
DISPLAY 0.808511 (3712 587);
PAINT WHITE (3712 587);
FORCEPROP 0 LAST $SEC 1
J 0
(3950 625);
DISPLAY 0.680851 (3950 625);
PAINT MONO (3950 625);
DISPLAY INVISIBLE (3950 625);
FORCEPROP 0 LAST CDS_SEC 1
J 0
(3950 625);
DISPLAY 1.021277 (3950 625);
DISPLAY INVISIBLE (3950 625);
FORCEADD Q_RES..1
(3650 875);
FORCEPROP 1 LAST VALUE 120
J 2
(4000 875);
DISPLAY 0.510638 (4000 875);
PAINT SKYBLUE (4000 875);
FORCEPROP 1 LAST MATERIAL CHIP
J 0
(3800 875);
DISPLAY 0.510638 (3800 875);
PAINT SKYBLUE (3800 875);
FORCEPROP 1 LAST PART_NUMBER CS11202FB02
J 0
(4475 950);
DISPLAY 0.510638 (4475 950);
PAINT WHITE (4475 950);
DISPLAY INVISIBLE (4475 950);
FORCEPROP 1 LAST PACK_TYPE 0402LF
J 0
(4700 650);
DISPLAY 0.510638 (4700 650);
PAINT SKYBLUE (4700 650);
DISPLAY INVISIBLE (4700 650);
FORCEPROP 1 LAST WATTAGE 1/16W
J 2
(3625 725);
DISPLAY 0.510638 (3625 725);
PAINT SKYBLUE (3625 725);
DISPLAY INVISIBLE (3625 725);
FORCEPROP 1 LAST PATH I117
J 0
(3600 1025);
DISPLAY 0.978723 (3600 1025);
PAINT WHITE (3600 1025);
DISPLAY INVISIBLE (3600 1025);
FORCEPROP 1 LAST TOLERANCE 1%
J 0
(3650 775);
DISPLAY 0.510638 (3650 775);
PAINT SKYBLUE (3650 775);
DISPLAY INVISIBLE (3650 775);
FORCEPROP 2 LAST CDS_LIB pure_quanta
J 0
(3650 875);
DISPLAY INVISIBLE (3650 875);
FORCEPROP 1 LAST LOCATION R347
J 0
(3375 875);
DISPLAY 0.702128 (3375 875);
PAINT YELLOW (3375 875);
FORCEPROP 1 LASTPIN (3550 875) $PN 1
J 0
(3562 887);
DISPLAY 0.808511 (3562 887);
PAINT WHITE (3562 887);
FORCEPROP 1 LASTPIN (3750 875) $PN 2
J 0
(3712 887);
DISPLAY 0.808511 (3712 887);
PAINT WHITE (3712 887);
FORCEPROP 0 LAST $SEC 1
J 0
(3950 925);
DISPLAY 0.680851 (3950 925);
PAINT MONO (3950 925);
DISPLAY INVISIBLE (3950 925);
FORCEPROP 0 LAST CDS_SEC 1
J 0
(3950 925);
DISPLAY 1.021277 (3950 925);
DISPLAY INVISIBLE (3950 925);
FORCEADD Q_RES..1
(3650 725);
FORCEPROP 1 LAST MATERIAL CHIP
J 0
(3800 725);
DISPLAY 0.510638 (3800 725);
PAINT SKYBLUE (3800 725);
FORCEPROP 1 LAST VALUE 120
J 2
(4000 725);
DISPLAY 0.510638 (4000 725);
PAINT SKYBLUE (4000 725);
FORCEPROP 1 LAST PART_NUMBER CS11202FB02
J 0
(4300 925);
DISPLAY 0.510638 (4300 925);
PAINT WHITE (4300 925);
DISPLAY INVISIBLE (4300 925);
FORCEPROP 1 LAST PACK_TYPE 0402LF
J 0
(4350 550);
DISPLAY 0.510638 (4350 550);
PAINT SKYBLUE (4350 550);
DISPLAY INVISIBLE (4350 550);
FORCEPROP 1 LAST WATTAGE 1/16W
J 2
(3625 575);
DISPLAY 0.510638 (3625 575);
PAINT SKYBLUE (3625 575);
DISPLAY INVISIBLE (3625 575);
FORCEPROP 1 LAST PATH I118
J 0
(3600 875);
DISPLAY 0.978723 (3600 875);
PAINT WHITE (3600 875);
DISPLAY INVISIBLE (3600 875);
FORCEPROP 1 LAST TOLERANCE 1%
J 0
(3650 625);
DISPLAY 0.510638 (3650 625);
PAINT SKYBLUE (3650 625);
DISPLAY INVISIBLE (3650 625);
FORCEPROP 2 LAST CDS_LIB pure_quanta
J 0
(3650 725);
DISPLAY INVISIBLE (3650 725);
FORCEPROP 1 LAST LOCATION R348
J 0
(3375 725);
DISPLAY 0.702128 (3375 725);
PAINT YELLOW (3375 725);
FORCEPROP 1 LASTPIN (3550 725) $PN 1
J 0
(3562 737);
DISPLAY 0.808511 (3562 737);
PAINT WHITE (3562 737);
FORCEPROP 1 LASTPIN (3750 725) $PN 2
J 0
(3712 737);
DISPLAY 0.808511 (3712 737);
PAINT WHITE (3712 737);
FORCEPROP 0 LAST $SEC 1
J 0
(3950 775);
DISPLAY 0.680851 (3950 775);
PAINT MONO (3950 775);
DISPLAY INVISIBLE (3950 775);
FORCEPROP 0 LAST CDS_SEC 1
J 0
(3950 775);
DISPLAY 1.021277 (3950 775);
DISPLAY INVISIBLE (3950 775);
FORCEADD Q_RES..1
(3650 1175);
FORCEPROP 1 LAST VALUE 120
J 2
(4000 1175);
DISPLAY 0.510638 (4000 1175);
PAINT SKYBLUE (4000 1175);
FORCEPROP 1 LAST MATERIAL CHIP
J 0
(3800 1175);
DISPLAY 0.510638 (3800 1175);
PAINT SKYBLUE (3800 1175);
FORCEPROP 1 LAST PART_NUMBER CS11202FB02
J 0
(3600 1275);
DISPLAY 0.510638 (3600 1275);
PAINT WHITE (3600 1275);
DISPLAY INVISIBLE (3600 1275);
FORCEPROP 1 LAST PACK_TYPE 0402LF
J 0
(3900 1025);
DISPLAY 0.510638 (3900 1025);
PAINT SKYBLUE (3900 1025);
DISPLAY INVISIBLE (3900 1025);
FORCEPROP 1 LAST WATTAGE 1/16W
J 2
(3625 1025);
DISPLAY 0.510638 (3625 1025);
PAINT SKYBLUE (3625 1025);
DISPLAY INVISIBLE (3625 1025);
FORCEPROP 1 LAST PATH I119
J 0
(3600 1325);
DISPLAY 0.978723 (3600 1325);
PAINT WHITE (3600 1325);
DISPLAY INVISIBLE (3600 1325);
FORCEPROP 1 LAST TOLERANCE 1%
J 0
(3650 1075);
DISPLAY 0.510638 (3650 1075);
PAINT SKYBLUE (3650 1075);
DISPLAY INVISIBLE (3650 1075);
FORCEPROP 2 LAST CDS_LIB pure_quanta
J 0
(3650 1175);
DISPLAY INVISIBLE (3650 1175);
FORCEPROP 1 LAST LOCATION R345
J 0
(3375 1175);
DISPLAY 0.702128 (3375 1175);
PAINT YELLOW (3375 1175);
FORCEPROP 1 LASTPIN (3550 1175) $PN 1
J 0
(3562 1187);
DISPLAY 0.808511 (3562 1187);
PAINT WHITE (3562 1187);
FORCEPROP 1 LASTPIN (3750 1175) $PN 2
J 0
(3712 1187);
DISPLAY 0.808511 (3712 1187);
PAINT WHITE (3712 1187);
FORCEPROP 0 LAST $SEC 1
J 0
(3950 1225);
DISPLAY 0.680851 (3950 1225);
PAINT MONO (3950 1225);
DISPLAY INVISIBLE (3950 1225);
FORCEPROP 0 LAST CDS_SEC 1
J 0
(3950 1225);
DISPLAY 1.021277 (3950 1225);
DISPLAY INVISIBLE (3950 1225);
FORCEADD OFFPAGE..1
(-2950 3950);
FORCEPROP 2 LAST $XR1 20 
J 0
(-3291 3950);
DISPLAY 0.638298 (-3291 3950);
PAINT MONO (-3291 3950);
FORCEPROP 2 LAST $XR0 12 
J 0
(-3201 3950);
DISPLAY 0.638298 (-3201 3950);
PAINT MONO (-3201 3950);
FORCEPROP 2 LAST PATH I12
J 0
(-3150 4000);
DISPLAY 1.021277 (-3150 4000);
DISPLAY INVISIBLE (-3150 4000);
FORCEPROP 1 LAST COMMENT_BODY TRUE
J 0
(-2825 3850);
DISPLAY 0.872340 (-2825 3850);
PAINT PEACH (-2825 3850);
DISPLAY INVISIBLE (-2825 3850);
FORCEPROP 1 LAST OFFPAGE TRUE
J 0
(-2625 3825);
DISPLAY 0.872340 (-2625 3825);
PAINT GREEN (-2625 3825);
DISPLAY INVISIBLE (-2625 3825);
FORCEPROP 2 LAST CDS_LIB standard
J 0
(-2950 3950);
DISPLAY INVISIBLE (-2950 3950);
FORCEADD Q_RES..1
(3650 1025);
FORCEPROP 1 LAST VALUE 120
J 2
(4000 1025);
DISPLAY 0.510638 (4000 1025);
PAINT SKYBLUE (4000 1025);
FORCEPROP 1 LAST MATERIAL CHIP
J 0
(3800 1025);
DISPLAY 0.510638 (3800 1025);
PAINT SKYBLUE (3800 1025);
FORCEPROP 1 LAST PART_NUMBER CS11202FB02
J 0
(3600 1125);
DISPLAY 0.510638 (3600 1125);
PAINT WHITE (3600 1125);
DISPLAY INVISIBLE (3600 1125);
FORCEPROP 1 LAST PACK_TYPE 0402LF
J 0
(3900 875);
DISPLAY 0.510638 (3900 875);
PAINT SKYBLUE (3900 875);
DISPLAY INVISIBLE (3900 875);
FORCEPROP 1 LAST WATTAGE 1/16W
J 2
(3625 875);
DISPLAY 0.510638 (3625 875);
PAINT SKYBLUE (3625 875);
DISPLAY INVISIBLE (3625 875);
FORCEPROP 1 LAST PATH I120
J 0
(3600 1175);
DISPLAY 0.978723 (3600 1175);
PAINT WHITE (3600 1175);
DISPLAY INVISIBLE (3600 1175);
FORCEPROP 1 LAST TOLERANCE 1%
J 0
(3650 925);
DISPLAY 0.510638 (3650 925);
PAINT SKYBLUE (3650 925);
DISPLAY INVISIBLE (3650 925);
FORCEPROP 2 LAST CDS_LIB pure_quanta
J 0
(3650 1025);
DISPLAY INVISIBLE (3650 1025);
FORCEPROP 1 LAST LOCATION R346
J 0
(3375 1025);
DISPLAY 0.702128 (3375 1025);
PAINT YELLOW (3375 1025);
FORCEPROP 1 LASTPIN (3550 1025) $PN 1
J 0
(3562 1037);
DISPLAY 0.808511 (3562 1037);
PAINT WHITE (3562 1037);
FORCEPROP 1 LASTPIN (3750 1025) $PN 2
J 0
(3712 1037);
DISPLAY 0.808511 (3712 1037);
PAINT WHITE (3712 1037);
FORCEPROP 0 LAST $SEC 1
J 0
(3950 1075);
DISPLAY 0.680851 (3950 1075);
PAINT MONO (3950 1075);
DISPLAY INVISIBLE (3950 1075);
FORCEPROP 0 LAST CDS_SEC 1
J 0
(3950 1075);
DISPLAY 1.021277 (3950 1075);
DISPLAY INVISIBLE (3950 1075);
FORCEADD Q_RES..1
(3650 1325);
FORCEPROP 1 LAST VALUE 120
J 2
(4000 1325);
DISPLAY 0.510638 (4000 1325);
PAINT SKYBLUE (4000 1325);
FORCEPROP 1 LAST MATERIAL CHIP
J 0
(3800 1325);
DISPLAY 0.510638 (3800 1325);
PAINT SKYBLUE (3800 1325);
FORCEPROP 1 LAST PART_NUMBER CS11202FB02
J 0
(3600 1425);
DISPLAY 0.510638 (3600 1425);
PAINT WHITE (3600 1425);
DISPLAY INVISIBLE (3600 1425);
FORCEPROP 1 LAST PACK_TYPE 0402LF
J 0
(3900 1175);
DISPLAY 0.510638 (3900 1175);
PAINT SKYBLUE (3900 1175);
DISPLAY INVISIBLE (3900 1175);
FORCEPROP 1 LAST WATTAGE 1/16W
J 2
(3625 1175);
DISPLAY 0.510638 (3625 1175);
PAINT SKYBLUE (3625 1175);
DISPLAY INVISIBLE (3625 1175);
FORCEPROP 1 LAST PATH I121
J 0
(3600 1475);
DISPLAY 0.978723 (3600 1475);
PAINT WHITE (3600 1475);
DISPLAY INVISIBLE (3600 1475);
FORCEPROP 1 LAST TOLERANCE 1%
J 0
(3650 1225);
DISPLAY 0.510638 (3650 1225);
PAINT SKYBLUE (3650 1225);
DISPLAY INVISIBLE (3650 1225);
FORCEPROP 2 LAST CDS_LIB pure_quanta
J 0
(3650 1325);
DISPLAY INVISIBLE (3650 1325);
FORCEPROP 1 LAST LOCATION R344
J 0
(3375 1325);
DISPLAY 0.702128 (3375 1325);
PAINT YELLOW (3375 1325);
FORCEPROP 1 LASTPIN (3550 1325) $PN 1
J 0
(3562 1337);
DISPLAY 0.808511 (3562 1337);
PAINT WHITE (3562 1337);
FORCEPROP 1 LASTPIN (3750 1325) $PN 2
J 0
(3712 1337);
DISPLAY 0.808511 (3712 1337);
PAINT WHITE (3712 1337);
FORCEPROP 0 LAST $SEC 1
J 0
(3950 1375);
DISPLAY 0.680851 (3950 1375);
PAINT MONO (3950 1375);
DISPLAY INVISIBLE (3950 1375);
FORCEPROP 0 LAST CDS_SEC 1
J 0
(3950 1375);
DISPLAY 1.021277 (3950 1375);
DISPLAY INVISIBLE (3950 1375);
FORCEADD Q_RES..1
(3650 1625);
FORCEPROP 1 LAST MATERIAL CHIP
J 0
(3800 1625);
DISPLAY 0.510638 (3800 1625);
PAINT SKYBLUE (3800 1625);
FORCEPROP 1 LAST VALUE 120
J 2
(4000 1625);
DISPLAY 0.510638 (4000 1625);
PAINT SKYBLUE (4000 1625);
FORCEPROP 1 LAST PART_NUMBER CS11202FB02
J 0
(3600 1725);
DISPLAY 0.510638 (3600 1725);
PAINT WHITE (3600 1725);
DISPLAY INVISIBLE (3600 1725);
FORCEPROP 1 LAST PACK_TYPE 0402LF
J 0
(3900 1475);
DISPLAY 0.510638 (3900 1475);
PAINT SKYBLUE (3900 1475);
DISPLAY INVISIBLE (3900 1475);
FORCEPROP 1 LAST WATTAGE 1/16W
J 2
(3625 1475);
DISPLAY 0.510638 (3625 1475);
PAINT SKYBLUE (3625 1475);
DISPLAY INVISIBLE (3625 1475);
FORCEPROP 1 LAST PATH I122
J 0
(3600 1775);
DISPLAY 0.978723 (3600 1775);
PAINT WHITE (3600 1775);
DISPLAY INVISIBLE (3600 1775);
FORCEPROP 1 LAST TOLERANCE 1%
J 0
(3650 1525);
DISPLAY 0.510638 (3650 1525);
PAINT SKYBLUE (3650 1525);
DISPLAY INVISIBLE (3650 1525);
FORCEPROP 2 LAST CDS_LIB pure_quanta
J 0
(3650 1625);
DISPLAY INVISIBLE (3650 1625);
FORCEPROP 1 LAST LOCATION R342
J 0
(3375 1625);
DISPLAY 0.702128 (3375 1625);
PAINT YELLOW (3375 1625);
FORCEPROP 1 LASTPIN (3550 1625) $PN 1
J 0
(3562 1637);
DISPLAY 0.808511 (3562 1637);
PAINT WHITE (3562 1637);
FORCEPROP 1 LASTPIN (3750 1625) $PN 2
J 0
(3712 1637);
DISPLAY 0.808511 (3712 1637);
PAINT WHITE (3712 1637);
FORCEPROP 0 LAST $SEC 1
J 0
(3950 1675);
DISPLAY 0.680851 (3950 1675);
PAINT MONO (3950 1675);
DISPLAY INVISIBLE (3950 1675);
FORCEPROP 0 LAST CDS_SEC 1
J 0
(3950 1675);
DISPLAY 1.021277 (3950 1675);
DISPLAY INVISIBLE (3950 1675);
FORCEADD Q_RES..1
(3650 1475);
FORCEPROP 1 LAST VALUE 120
J 2
(4000 1475);
DISPLAY 0.510638 (4000 1475);
PAINT SKYBLUE (4000 1475);
FORCEPROP 1 LAST MATERIAL CHIP
J 0
(3800 1475);
DISPLAY 0.510638 (3800 1475);
PAINT SKYBLUE (3800 1475);
FORCEPROP 1 LAST PART_NUMBER CS11202FB02
J 0
(3600 1575);
DISPLAY 0.510638 (3600 1575);
PAINT WHITE (3600 1575);
DISPLAY INVISIBLE (3600 1575);
FORCEPROP 1 LAST PACK_TYPE 0402LF
J 0
(3900 1325);
DISPLAY 0.510638 (3900 1325);
PAINT SKYBLUE (3900 1325);
DISPLAY INVISIBLE (3900 1325);
FORCEPROP 1 LAST WATTAGE 1/16W
J 2
(3625 1325);
DISPLAY 0.510638 (3625 1325);
PAINT SKYBLUE (3625 1325);
DISPLAY INVISIBLE (3625 1325);
FORCEPROP 1 LAST PATH I123
J 0
(3600 1625);
DISPLAY 0.978723 (3600 1625);
PAINT WHITE (3600 1625);
DISPLAY INVISIBLE (3600 1625);
FORCEPROP 1 LAST TOLERANCE 1%
J 0
(3650 1375);
DISPLAY 0.510638 (3650 1375);
PAINT SKYBLUE (3650 1375);
DISPLAY INVISIBLE (3650 1375);
FORCEPROP 2 LAST CDS_LIB pure_quanta
J 0
(3650 1475);
DISPLAY INVISIBLE (3650 1475);
FORCEPROP 1 LAST LOCATION R343
J 0
(3375 1475);
DISPLAY 0.702128 (3375 1475);
PAINT YELLOW (3375 1475);
FORCEPROP 1 LASTPIN (3550 1475) $PN 1
J 0
(3562 1487);
DISPLAY 0.808511 (3562 1487);
PAINT WHITE (3562 1487);
FORCEPROP 1 LASTPIN (3750 1475) $PN 2
J 0
(3712 1487);
DISPLAY 0.808511 (3712 1487);
PAINT WHITE (3712 1487);
FORCEPROP 0 LAST $SEC 1
J 0
(3950 1525);
DISPLAY 0.680851 (3950 1525);
PAINT MONO (3950 1525);
DISPLAY INVISIBLE (3950 1525);
FORCEPROP 0 LAST CDS_SEC 1
J 0
(3950 1525);
DISPLAY 1.021277 (3950 1525);
DISPLAY INVISIBLE (3950 1525);
FORCEADD Q_RES..1
(3650 1925);
FORCEPROP 1 LAST MATERIAL CHIP
J 0
(3800 1925);
DISPLAY 0.510638 (3800 1925);
PAINT SKYBLUE (3800 1925);
FORCEPROP 1 LAST VALUE 120
J 2
(4000 1925);
DISPLAY 0.510638 (4000 1925);
PAINT SKYBLUE (4000 1925);
FORCEPROP 1 LAST PART_NUMBER CS11202FB02
J 0
(3600 2025);
DISPLAY 0.510638 (3600 2025);
PAINT WHITE (3600 2025);
DISPLAY INVISIBLE (3600 2025);
FORCEPROP 1 LAST PACK_TYPE 0402LF
J 0
(3900 1775);
DISPLAY 0.510638 (3900 1775);
PAINT SKYBLUE (3900 1775);
DISPLAY INVISIBLE (3900 1775);
FORCEPROP 1 LAST WATTAGE 1/16W
J 2
(3625 1775);
DISPLAY 0.510638 (3625 1775);
PAINT SKYBLUE (3625 1775);
DISPLAY INVISIBLE (3625 1775);
FORCEPROP 1 LAST PATH I124
J 0
(3600 2075);
DISPLAY 0.978723 (3600 2075);
PAINT WHITE (3600 2075);
DISPLAY INVISIBLE (3600 2075);
FORCEPROP 1 LAST TOLERANCE 1%
J 0
(3650 1825);
DISPLAY 0.510638 (3650 1825);
PAINT SKYBLUE (3650 1825);
DISPLAY INVISIBLE (3650 1825);
FORCEPROP 2 LAST CDS_LIB pure_quanta
J 0
(3650 1925);
DISPLAY INVISIBLE (3650 1925);
FORCEPROP 1 LAST LOCATION R340
J 0
(3375 1925);
DISPLAY 0.702128 (3375 1925);
PAINT YELLOW (3375 1925);
FORCEPROP 1 LASTPIN (3550 1925) $PN 1
J 0
(3562 1937);
DISPLAY 0.808511 (3562 1937);
PAINT WHITE (3562 1937);
FORCEPROP 1 LASTPIN (3750 1925) $PN 2
J 0
(3712 1937);
DISPLAY 0.808511 (3712 1937);
PAINT WHITE (3712 1937);
FORCEPROP 0 LAST $SEC 1
J 0
(3950 1975);
DISPLAY 0.680851 (3950 1975);
PAINT MONO (3950 1975);
DISPLAY INVISIBLE (3950 1975);
FORCEPROP 0 LAST CDS_SEC 1
J 0
(3950 1975);
DISPLAY 1.021277 (3950 1975);
DISPLAY INVISIBLE (3950 1975);
FORCEADD Q_RES..1
(3650 1775);
FORCEPROP 1 LAST MATERIAL CHIP
J 0
(3800 1775);
DISPLAY 0.510638 (3800 1775);
PAINT SKYBLUE (3800 1775);
FORCEPROP 1 LAST VALUE 120
J 2
(4000 1775);
DISPLAY 0.510638 (4000 1775);
PAINT SKYBLUE (4000 1775);
FORCEPROP 1 LAST PART_NUMBER CS11202FB02
J 0
(3600 1875);
DISPLAY 0.510638 (3600 1875);
PAINT WHITE (3600 1875);
DISPLAY INVISIBLE (3600 1875);
FORCEPROP 1 LAST PACK_TYPE 0402LF
J 0
(3900 1625);
DISPLAY 0.510638 (3900 1625);
PAINT SKYBLUE (3900 1625);
DISPLAY INVISIBLE (3900 1625);
FORCEPROP 1 LAST WATTAGE 1/16W
J 2
(3625 1625);
DISPLAY 0.510638 (3625 1625);
PAINT SKYBLUE (3625 1625);
DISPLAY INVISIBLE (3625 1625);
FORCEPROP 1 LAST PATH I125
J 0
(3600 1925);
DISPLAY 0.978723 (3600 1925);
PAINT WHITE (3600 1925);
DISPLAY INVISIBLE (3600 1925);
FORCEPROP 1 LAST TOLERANCE 1%
J 0
(3650 1675);
DISPLAY 0.510638 (3650 1675);
PAINT SKYBLUE (3650 1675);
DISPLAY INVISIBLE (3650 1675);
FORCEPROP 2 LAST CDS_LIB pure_quanta
J 0
(3650 1775);
DISPLAY INVISIBLE (3650 1775);
FORCEPROP 1 LAST LOCATION R341
J 0
(3375 1775);
DISPLAY 0.702128 (3375 1775);
PAINT YELLOW (3375 1775);
FORCEPROP 1 LASTPIN (3550 1775) $PN 1
J 0
(3562 1787);
DISPLAY 0.808511 (3562 1787);
PAINT WHITE (3562 1787);
FORCEPROP 1 LASTPIN (3750 1775) $PN 2
J 0
(3712 1787);
DISPLAY 0.808511 (3712 1787);
PAINT WHITE (3712 1787);
FORCEPROP 0 LAST $SEC 1
J 0
(3950 1825);
DISPLAY 0.680851 (3950 1825);
PAINT MONO (3950 1825);
DISPLAY INVISIBLE (3950 1825);
FORCEPROP 0 LAST CDS_SEC 1
J 0
(3950 1825);
DISPLAY 1.021277 (3950 1825);
DISPLAY INVISIBLE (3950 1825);
FORCEADD UNIVERSAL_GND..1
(3225 2425);
FORCEPROP 3 LASTPIN (3225 2475) SIG_NAME GND\g
J 0
(3235 2485);
DISPLAY 0.659574 (3235 2485);
PAINT MONO (3235 2485);
DISPLAY INVISIBLE (3235 2485);
FORCEPROP 1 LAST PATH I126
J 0
(3300 2425);
DISPLAY 0.872340 (3300 2425);
PAINT AQUA (3300 2425);
DISPLAY INVISIBLE (3300 2425);
FORCEPROP 1 LAST HDL_POWER GND
J 1
(3250 2350);
DISPLAY 0.702128 (3250 2350);
PAINT GREEN (3250 2350);
DISPLAY INVISIBLE (3250 2350);
FORCEPROP 2 LAST CDS_LIB logical_power
J 0
(3225 2425);
DISPLAY INVISIBLE (3225 2425);
FORCEADD Q_RES..1
(4325 575);
FORCEPROP 1 LAST VALUE 120
J 2
(4650 575);
DISPLAY 0.510638 (4650 575);
PAINT SKYBLUE (4650 575);
FORCEPROP 1 LAST MATERIAL CHIP
J 0
(4450 575);
DISPLAY 0.510638 (4450 575);
PAINT SKYBLUE (4450 575);
FORCEPROP 1 LAST PART_NUMBER CS11202FB02
J 0
(4800 725);
DISPLAY 0.510638 (4800 725);
PAINT WHITE (4800 725);
DISPLAY INVISIBLE (4800 725);
FORCEPROP 1 LAST PACK_TYPE 0402LF
J 0
(4575 425);
DISPLAY 0.510638 (4575 425);
PAINT SKYBLUE (4575 425);
DISPLAY INVISIBLE (4575 425);
FORCEPROP 1 LAST WATTAGE 1/16W
J 2
(4300 425);
DISPLAY 0.510638 (4300 425);
PAINT SKYBLUE (4300 425);
DISPLAY INVISIBLE (4300 425);
FORCEPROP 1 LAST PATH I127
J 0
(4275 725);
DISPLAY 0.978723 (4275 725);
PAINT WHITE (4275 725);
DISPLAY INVISIBLE (4275 725);
FORCEPROP 1 LAST TOLERANCE 1%
J 0
(4325 475);
DISPLAY 0.510638 (4325 475);
PAINT SKYBLUE (4325 475);
DISPLAY INVISIBLE (4325 475);
FORCEPROP 2 LAST CDS_LIB pure_quanta
J 0
(4325 575);
DISPLAY INVISIBLE (4325 575);
FORCEPROP 1 LAST LOCATION R374
J 0
(4075 575);
DISPLAY 0.702128 (4075 575);
PAINT YELLOW (4075 575);
FORCEPROP 1 LASTPIN (4225 575) $PN 1
J 0
(4237 587);
DISPLAY 0.808511 (4237 587);
PAINT WHITE (4237 587);
FORCEPROP 1 LASTPIN (4425 575) $PN 2
J 0
(4387 587);
DISPLAY 0.808511 (4387 587);
PAINT WHITE (4387 587);
FORCEPROP 0 LAST $SEC 1
J 0
(4625 625);
DISPLAY 0.680851 (4625 625);
PAINT MONO (4625 625);
DISPLAY INVISIBLE (4625 625);
FORCEPROP 0 LAST CDS_SEC 1
J 0
(4625 625);
DISPLAY 1.021277 (4625 625);
DISPLAY INVISIBLE (4625 625);
FORCEADD Q_RES..1
(4325 725);
FORCEPROP 1 LAST MATERIAL CHIP
J 0
(4450 725);
DISPLAY 0.510638 (4450 725);
PAINT SKYBLUE (4450 725);
FORCEPROP 1 LAST VALUE 120
J 2
(4650 725);
DISPLAY 0.510638 (4650 725);
PAINT SKYBLUE (4650 725);
FORCEPROP 1 LAST PART_NUMBER CS11202FB02
J 0
(5000 800);
DISPLAY 0.510638 (5000 800);
PAINT WHITE (5000 800);
DISPLAY INVISIBLE (5000 800);
FORCEPROP 1 LAST PACK_TYPE 0402LF
J 0
(5075 550);
DISPLAY 0.510638 (5075 550);
PAINT SKYBLUE (5075 550);
DISPLAY INVISIBLE (5075 550);
FORCEPROP 1 LAST WATTAGE 1/16W
J 2
(4300 575);
DISPLAY 0.510638 (4300 575);
PAINT SKYBLUE (4300 575);
DISPLAY INVISIBLE (4300 575);
FORCEPROP 1 LAST PATH I128
J 0
(4275 875);
DISPLAY 0.978723 (4275 875);
PAINT WHITE (4275 875);
DISPLAY INVISIBLE (4275 875);
FORCEPROP 1 LAST TOLERANCE 1%
J 0
(4325 625);
DISPLAY 0.510638 (4325 625);
PAINT SKYBLUE (4325 625);
DISPLAY INVISIBLE (4325 625);
FORCEPROP 2 LAST CDS_LIB pure_quanta
J 0
(4325 725);
DISPLAY INVISIBLE (4325 725);
FORCEPROP 1 LAST LOCATION R373
J 0
(4075 725);
DISPLAY 0.702128 (4075 725);
PAINT YELLOW (4075 725);
FORCEPROP 1 LASTPIN (4225 725) $PN 1
J 0
(4237 737);
DISPLAY 0.808511 (4237 737);
PAINT WHITE (4237 737);
FORCEPROP 1 LASTPIN (4425 725) $PN 2
J 0
(4387 737);
DISPLAY 0.808511 (4387 737);
PAINT WHITE (4387 737);
FORCEPROP 0 LAST $SEC 1
J 0
(4625 775);
DISPLAY 0.680851 (4625 775);
PAINT MONO (4625 775);
DISPLAY INVISIBLE (4625 775);
FORCEPROP 0 LAST CDS_SEC 1
J 0
(4625 775);
DISPLAY 1.021277 (4625 775);
DISPLAY INVISIBLE (4625 775);
FORCEADD Q_RES..1
(4325 875);
FORCEPROP 1 LAST MATERIAL CHIP
J 0
(4450 875);
DISPLAY 0.510638 (4450 875);
PAINT SKYBLUE (4450 875);
FORCEPROP 1 LAST VALUE 120
J 2
(4650 875);
DISPLAY 0.510638 (4650 875);
PAINT SKYBLUE (4650 875);
FORCEPROP 1 LAST PART_NUMBER CS11202FB02
J 0
(5075 900);
DISPLAY 0.510638 (5075 900);
PAINT WHITE (5075 900);
DISPLAY INVISIBLE (5075 900);
FORCEPROP 1 LAST PACK_TYPE 0402LF
J 0
(5175 775);
DISPLAY 0.510638 (5175 775);
PAINT SKYBLUE (5175 775);
DISPLAY INVISIBLE (5175 775);
FORCEPROP 1 LAST WATTAGE 1/16W
J 2
(4300 725);
DISPLAY 0.510638 (4300 725);
PAINT SKYBLUE (4300 725);
DISPLAY INVISIBLE (4300 725);
FORCEPROP 1 LAST PATH I129
J 0
(4275 1025);
DISPLAY 0.978723 (4275 1025);
PAINT WHITE (4275 1025);
DISPLAY INVISIBLE (4275 1025);
FORCEPROP 1 LAST TOLERANCE 1%
J 0
(4325 775);
DISPLAY 0.510638 (4325 775);
PAINT SKYBLUE (4325 775);
DISPLAY INVISIBLE (4325 775);
FORCEPROP 2 LAST CDS_LIB pure_quanta
J 0
(4325 875);
DISPLAY INVISIBLE (4325 875);
FORCEPROP 1 LAST LOCATION R372
J 0
(4075 875);
DISPLAY 0.702128 (4075 875);
PAINT YELLOW (4075 875);
FORCEPROP 1 LASTPIN (4225 875) $PN 1
J 0
(4237 887);
DISPLAY 0.808511 (4237 887);
PAINT WHITE (4237 887);
FORCEPROP 1 LASTPIN (4425 875) $PN 2
J 0
(4387 887);
DISPLAY 0.808511 (4387 887);
PAINT WHITE (4387 887);
FORCEPROP 0 LAST $SEC 1
J 0
(4625 925);
DISPLAY 0.680851 (4625 925);
PAINT MONO (4625 925);
DISPLAY INVISIBLE (4625 925);
FORCEPROP 0 LAST CDS_SEC 1
J 0
(4625 925);
DISPLAY 1.021277 (4625 925);
DISPLAY INVISIBLE (4625 925);
FORCEADD Q_RES..1
(-2425 -1050);
FORCEPROP 1 LAST PART_NUMBER CS00002JB13
J 0
(-2750 -1125);
DISPLAY 0.510638 (-2750 -1125);
PAINT WHITE (-2750 -1125);
FORCEPROP 1 LAST PACK_TYPE 0402LF
J 0
(-2800 -1200);
DISPLAY 0.510638 (-2800 -1200);
PAINT SKYBLUE (-2800 -1200);
FORCEPROP 1 LAST WATTAGE 1/16W
J 2
(-2375 -1200);
DISPLAY 0.510638 (-2375 -1200);
PAINT SKYBLUE (-2375 -1200);
FORCEPROP 1 LAST TOLERANCE 5%
J 0
(-2325 -1200);
DISPLAY 0.510638 (-2325 -1200);
PAINT SKYBLUE (-2325 -1200);
FORCEPROP 1 LAST MATERIAL CHIP
J 0
(-2625 -1200);
DISPLAY 0.510638 (-2625 -1200);
PAINT SKYBLUE (-2625 -1200);
FORCEPROP 1 LAST VALUE 0
J 2
(-2175 -1050);
DISPLAY 0.510638 (-2175 -1050);
PAINT SKYBLUE (-2175 -1050);
FORCEPROP 1 LAST PATH I13
J 0
(-2475 -900);
DISPLAY 0.978723 (-2475 -900);
PAINT WHITE (-2475 -900);
DISPLAY INVISIBLE (-2475 -900);
FORCEPROP 2 LAST SEC_TYPE 0402LF
J 0
(-2475 -850);
DISPLAY 0.680851 (-2475 -850);
DISPLAY INVISIBLE (-2475 -850);
FORCEPROP 2 LAST CDS_LIB pure_quanta
J 0
(-2425 -1050);
DISPLAY INVISIBLE (-2425 -1050);
FORCEPROP 1 LAST LOCATION R2
J 0
(-2625 -1050);
DISPLAY 0.702128 (-2625 -1050);
PAINT YELLOW (-2625 -1050);
FORCEPROP 1 LASTPIN (-2525 -1050) $PN 1
J 0
(-2513 -1038);
DISPLAY 0.808511 (-2513 -1038);
PAINT WHITE (-2513 -1038);
FORCEPROP 1 LASTPIN (-2325 -1050) $PN 2
J 0
(-2363 -1038);
DISPLAY 0.808511 (-2363 -1038);
PAINT WHITE (-2363 -1038);
FORCEPROP 2 LAST SEC 1
J 0
(-2475 -850);
DISPLAY 0.680851 (-2475 -850);
PAINT MONO (-2475 -850);
DISPLAY INVISIBLE (-2475 -850);
FORCEADD Q_RES..1
(4325 1025);
FORCEPROP 1 LAST MATERIAL CHIP
J 0
(4450 1025);
DISPLAY 0.510638 (4450 1025);
PAINT SKYBLUE (4450 1025);
FORCEPROP 1 LAST VALUE 120
J 2
(4650 1025);
DISPLAY 0.510638 (4650 1025);
PAINT SKYBLUE (4650 1025);
FORCEPROP 1 LAST PART_NUMBER CS11202FB02
J 0
(4275 1125);
DISPLAY 0.510638 (4275 1125);
PAINT WHITE (4275 1125);
DISPLAY INVISIBLE (4275 1125);
FORCEPROP 1 LAST PACK_TYPE 0402LF
J 0
(4575 875);
DISPLAY 0.510638 (4575 875);
PAINT SKYBLUE (4575 875);
DISPLAY INVISIBLE (4575 875);
FORCEPROP 1 LAST WATTAGE 1/16W
J 2
(4300 875);
DISPLAY 0.510638 (4300 875);
PAINT SKYBLUE (4300 875);
DISPLAY INVISIBLE (4300 875);
FORCEPROP 1 LAST PATH I130
J 0
(4275 1175);
DISPLAY 0.978723 (4275 1175);
PAINT WHITE (4275 1175);
DISPLAY INVISIBLE (4275 1175);
FORCEPROP 1 LAST TOLERANCE 1%
J 0
(4325 925);
DISPLAY 0.510638 (4325 925);
PAINT SKYBLUE (4325 925);
DISPLAY INVISIBLE (4325 925);
FORCEPROP 2 LAST CDS_LIB pure_quanta
J 0
(4325 1025);
DISPLAY INVISIBLE (4325 1025);
FORCEPROP 1 LAST LOCATION R371
J 0
(4075 1025);
DISPLAY 0.702128 (4075 1025);
PAINT YELLOW (4075 1025);
FORCEPROP 1 LASTPIN (4225 1025) $PN 1
J 0
(4237 1037);
DISPLAY 0.808511 (4237 1037);
PAINT WHITE (4237 1037);
FORCEPROP 1 LASTPIN (4425 1025) $PN 2
J 0
(4387 1037);
DISPLAY 0.808511 (4387 1037);
PAINT WHITE (4387 1037);
FORCEPROP 0 LAST $SEC 1
J 0
(4625 1075);
DISPLAY 0.680851 (4625 1075);
PAINT MONO (4625 1075);
DISPLAY INVISIBLE (4625 1075);
FORCEPROP 0 LAST CDS_SEC 1
J 0
(4625 1075);
DISPLAY 1.021277 (4625 1075);
DISPLAY INVISIBLE (4625 1075);
FORCEADD Q_RES..1
(4325 1175);
FORCEPROP 1 LAST MATERIAL CHIP
J 0
(4450 1175);
DISPLAY 0.510638 (4450 1175);
PAINT SKYBLUE (4450 1175);
FORCEPROP 1 LAST VALUE 120
J 2
(4650 1175);
DISPLAY 0.510638 (4650 1175);
PAINT SKYBLUE (4650 1175);
FORCEPROP 1 LAST PART_NUMBER CS11202FB02
J 0
(4275 1275);
DISPLAY 0.510638 (4275 1275);
PAINT WHITE (4275 1275);
DISPLAY INVISIBLE (4275 1275);
FORCEPROP 1 LAST PACK_TYPE 0402LF
J 0
(4575 1025);
DISPLAY 0.510638 (4575 1025);
PAINT SKYBLUE (4575 1025);
DISPLAY INVISIBLE (4575 1025);
FORCEPROP 1 LAST WATTAGE 1/16W
J 2
(4300 1025);
DISPLAY 0.510638 (4300 1025);
PAINT SKYBLUE (4300 1025);
DISPLAY INVISIBLE (4300 1025);
FORCEPROP 1 LAST PATH I131
J 0
(4275 1325);
DISPLAY 0.978723 (4275 1325);
PAINT WHITE (4275 1325);
DISPLAY INVISIBLE (4275 1325);
FORCEPROP 1 LAST TOLERANCE 1%
J 0
(4325 1075);
DISPLAY 0.510638 (4325 1075);
PAINT SKYBLUE (4325 1075);
DISPLAY INVISIBLE (4325 1075);
FORCEPROP 2 LAST CDS_LIB pure_quanta
J 0
(4325 1175);
DISPLAY INVISIBLE (4325 1175);
FORCEPROP 1 LAST LOCATION R370
J 0
(4075 1175);
DISPLAY 0.702128 (4075 1175);
PAINT YELLOW (4075 1175);
FORCEPROP 1 LASTPIN (4225 1175) $PN 1
J 0
(4237 1187);
DISPLAY 0.808511 (4237 1187);
PAINT WHITE (4237 1187);
FORCEPROP 1 LASTPIN (4425 1175) $PN 2
J 0
(4387 1187);
DISPLAY 0.808511 (4387 1187);
PAINT WHITE (4387 1187);
FORCEPROP 0 LAST $SEC 1
J 0
(4625 1225);
DISPLAY 0.680851 (4625 1225);
PAINT MONO (4625 1225);
DISPLAY INVISIBLE (4625 1225);
FORCEPROP 0 LAST CDS_SEC 1
J 0
(4625 1225);
DISPLAY 1.021277 (4625 1225);
DISPLAY INVISIBLE (4625 1225);
FORCEADD Q_RES..1
(4325 1325);
FORCEPROP 1 LAST MATERIAL CHIP
J 0
(4450 1325);
DISPLAY 0.510638 (4450 1325);
PAINT SKYBLUE (4450 1325);
FORCEPROP 1 LAST VALUE 120
J 2
(4650 1325);
DISPLAY 0.510638 (4650 1325);
PAINT SKYBLUE (4650 1325);
FORCEPROP 1 LAST PART_NUMBER CS11202FB02
J 0
(4275 1425);
DISPLAY 0.510638 (4275 1425);
PAINT WHITE (4275 1425);
DISPLAY INVISIBLE (4275 1425);
FORCEPROP 1 LAST PACK_TYPE 0402LF
J 0
(4575 1175);
DISPLAY 0.510638 (4575 1175);
PAINT SKYBLUE (4575 1175);
DISPLAY INVISIBLE (4575 1175);
FORCEPROP 1 LAST WATTAGE 1/16W
J 2
(4300 1175);
DISPLAY 0.510638 (4300 1175);
PAINT SKYBLUE (4300 1175);
DISPLAY INVISIBLE (4300 1175);
FORCEPROP 1 LAST PATH I132
J 0
(4275 1475);
DISPLAY 0.978723 (4275 1475);
PAINT WHITE (4275 1475);
DISPLAY INVISIBLE (4275 1475);
FORCEPROP 1 LAST TOLERANCE 1%
J 0
(4325 1225);
DISPLAY 0.510638 (4325 1225);
PAINT SKYBLUE (4325 1225);
DISPLAY INVISIBLE (4325 1225);
FORCEPROP 2 LAST CDS_LIB pure_quanta
J 0
(4325 1325);
DISPLAY INVISIBLE (4325 1325);
FORCEPROP 1 LAST LOCATION R369
J 0
(4075 1325);
DISPLAY 0.702128 (4075 1325);
PAINT YELLOW (4075 1325);
FORCEPROP 1 LASTPIN (4225 1325) $PN 1
J 0
(4237 1337);
DISPLAY 0.808511 (4237 1337);
PAINT WHITE (4237 1337);
FORCEPROP 1 LASTPIN (4425 1325) $PN 2
J 0
(4387 1337);
DISPLAY 0.808511 (4387 1337);
PAINT WHITE (4387 1337);
FORCEPROP 0 LAST $SEC 1
J 0
(4625 1375);
DISPLAY 0.680851 (4625 1375);
PAINT MONO (4625 1375);
DISPLAY INVISIBLE (4625 1375);
FORCEPROP 0 LAST CDS_SEC 1
J 0
(4625 1375);
DISPLAY 1.021277 (4625 1375);
DISPLAY INVISIBLE (4625 1375);
FORCEADD UNIVERSAL_GND..1
(4975 850);
FORCEPROP 3 LASTPIN (4975 900) SIG_NAME GND\g
J 0
(4985 910);
DISPLAY 0.659574 (4985 910);
PAINT MONO (4985 910);
DISPLAY INVISIBLE (4985 910);
FORCEPROP 1 LAST PATH I133
J 0
(5050 850);
DISPLAY 0.872340 (5050 850);
PAINT AQUA (5050 850);
DISPLAY INVISIBLE (5050 850);
FORCEPROP 1 LAST HDL_POWER GND
J 1
(5000 775);
DISPLAY 0.702128 (5000 775);
PAINT GREEN (5000 775);
DISPLAY INVISIBLE (5000 775);
FORCEPROP 2 LAST CDS_LIB logical_power
J 0
(4975 850);
DISPLAY INVISIBLE (4975 850);
FORCEADD Q_CAP..1
(4975 1075);
FORCEPROP 1 LAST VOLTAGE 6.3V
J 0
(5025 1075);
DISPLAY 0.510638 (5025 1075);
PAINT SKYBLUE (5025 1075);
FORCEPROP 1 LAST PACK_TYPE C0402
J 0
(5025 925);
DISPLAY 0.510638 (5025 925);
PAINT SKYBLUE (5025 925);
FORCEPROP 1 LAST TOLERANCE 20%
J 0
(5025 1025);
DISPLAY 0.510638 (5025 1025);
PAINT SKYBLUE (5025 1025);
FORCEPROP 1 LAST VALUE 10UF
J 0
(5025 1125);
DISPLAY 0.510638 (5025 1125);
PAINT SKYBLUE (5025 1125);
FORCEPROP 1 LAST MATERIAL X6S
J 0
(5025 975);
DISPLAY 0.510638 (5025 975);
PAINT SKYBLUE (5025 975);
FORCEPROP 1 LAST PATH I134
J 0
(5025 1225);
DISPLAY 0.978723 (5025 1225);
PAINT WHITE (5025 1225);
DISPLAY INVISIBLE (5025 1225);
FORCEPROP 2 LAST SEC_TYPE C0402
J 0
(5025 1275);
DISPLAY 0.680851 (5025 1275);
DISPLAY INVISIBLE (5025 1275);
FORCEPROP 2 LAST CDS_LIB pure_quanta
J 0
(4975 1075);
DISPLAY INVISIBLE (4975 1075);
FORCEPROP 1 LAST PART_NUMBER CH6101MEB01
J 0
(5025 925);
DISPLAY 0.510638 (5025 925);
PAINT WHITE (5025 925);
DISPLAY INVISIBLE (5025 925);
FORCEPROP 1 LAST LOCATION C15
J 0
(5025 1175);
DISPLAY 0.702128 (5025 1175);
PAINT YELLOW (5025 1175);
FORCEPROP 1 LASTPIN (4975 1175) $PN 1
J 0
(4985 1155);
DISPLAY 0.808511 (4985 1155);
PAINT WHITE (4985 1155);
FORCEPROP 1 LASTPIN (4975 975) $PN 2
J 0
(4985 955);
DISPLAY 0.808511 (4985 955);
PAINT WHITE (4985 955);
FORCEPROP 2 LAST SEC 1
J 0
(5025 1275);
DISPLAY 0.680851 (5025 1275);
PAINT MONO (5025 1275);
DISPLAY INVISIBLE (5025 1275);
FORCEADD Q_RES..1
(4325 1475);
FORCEPROP 1 LAST MATERIAL CHIP
J 0
(4450 1475);
DISPLAY 0.510638 (4450 1475);
PAINT SKYBLUE (4450 1475);
FORCEPROP 1 LAST VALUE 120
J 2
(4650 1475);
DISPLAY 0.510638 (4650 1475);
PAINT SKYBLUE (4650 1475);
FORCEPROP 1 LAST PART_NUMBER CS11202FB02
J 0
(4275 1575);
DISPLAY 0.510638 (4275 1575);
PAINT WHITE (4275 1575);
DISPLAY INVISIBLE (4275 1575);
FORCEPROP 1 LAST PACK_TYPE 0402LF
J 0
(4575 1325);
DISPLAY 0.510638 (4575 1325);
PAINT SKYBLUE (4575 1325);
DISPLAY INVISIBLE (4575 1325);
FORCEPROP 1 LAST WATTAGE 1/16W
J 2
(4300 1325);
DISPLAY 0.510638 (4300 1325);
PAINT SKYBLUE (4300 1325);
DISPLAY INVISIBLE (4300 1325);
FORCEPROP 1 LAST PATH I135
J 0
(4275 1625);
DISPLAY 0.978723 (4275 1625);
PAINT WHITE (4275 1625);
DISPLAY INVISIBLE (4275 1625);
FORCEPROP 1 LAST TOLERANCE 1%
J 0
(4325 1375);
DISPLAY 0.510638 (4325 1375);
PAINT SKYBLUE (4325 1375);
DISPLAY INVISIBLE (4325 1375);
FORCEPROP 2 LAST CDS_LIB pure_quanta
J 0
(4325 1475);
DISPLAY INVISIBLE (4325 1475);
FORCEPROP 1 LAST LOCATION R368
J 0
(4075 1475);
DISPLAY 0.702128 (4075 1475);
PAINT YELLOW (4075 1475);
FORCEPROP 1 LASTPIN (4225 1475) $PN 1
J 0
(4237 1487);
DISPLAY 0.808511 (4237 1487);
PAINT WHITE (4237 1487);
FORCEPROP 1 LASTPIN (4425 1475) $PN 2
J 0
(4387 1487);
DISPLAY 0.808511 (4387 1487);
PAINT WHITE (4387 1487);
FORCEPROP 0 LAST $SEC 1
J 0
(4625 1525);
DISPLAY 0.680851 (4625 1525);
PAINT MONO (4625 1525);
DISPLAY INVISIBLE (4625 1525);
FORCEPROP 0 LAST CDS_SEC 1
J 0
(4625 1525);
DISPLAY 1.021277 (4625 1525);
DISPLAY INVISIBLE (4625 1525);
FORCEADD Q_RES..1
(4325 1625);
FORCEPROP 1 LAST MATERIAL CHIP
J 0
(4450 1625);
DISPLAY 0.510638 (4450 1625);
PAINT SKYBLUE (4450 1625);
FORCEPROP 1 LAST VALUE 120
J 2
(4650 1625);
DISPLAY 0.510638 (4650 1625);
PAINT SKYBLUE (4650 1625);
FORCEPROP 1 LAST PART_NUMBER CS11202FB02
J 0
(4275 1725);
DISPLAY 0.510638 (4275 1725);
PAINT WHITE (4275 1725);
DISPLAY INVISIBLE (4275 1725);
FORCEPROP 1 LAST PACK_TYPE 0402LF
J 0
(4575 1475);
DISPLAY 0.510638 (4575 1475);
PAINT SKYBLUE (4575 1475);
DISPLAY INVISIBLE (4575 1475);
FORCEPROP 1 LAST WATTAGE 1/16W
J 2
(4300 1475);
DISPLAY 0.510638 (4300 1475);
PAINT SKYBLUE (4300 1475);
DISPLAY INVISIBLE (4300 1475);
FORCEPROP 1 LAST PATH I136
J 0
(4275 1775);
DISPLAY 0.978723 (4275 1775);
PAINT WHITE (4275 1775);
DISPLAY INVISIBLE (4275 1775);
FORCEPROP 1 LAST TOLERANCE 1%
J 0
(4325 1525);
DISPLAY 0.510638 (4325 1525);
PAINT SKYBLUE (4325 1525);
DISPLAY INVISIBLE (4325 1525);
FORCEPROP 2 LAST CDS_LIB pure_quanta
J 0
(4325 1625);
DISPLAY INVISIBLE (4325 1625);
FORCEPROP 1 LAST LOCATION R367
J 0
(4075 1625);
DISPLAY 0.702128 (4075 1625);
PAINT YELLOW (4075 1625);
FORCEPROP 1 LASTPIN (4225 1625) $PN 1
J 0
(4237 1637);
DISPLAY 0.808511 (4237 1637);
PAINT WHITE (4237 1637);
FORCEPROP 1 LASTPIN (4425 1625) $PN 2
J 0
(4387 1637);
DISPLAY 0.808511 (4387 1637);
PAINT WHITE (4387 1637);
FORCEPROP 0 LAST $SEC 1
J 0
(4625 1675);
DISPLAY 0.680851 (4625 1675);
PAINT MONO (4625 1675);
DISPLAY INVISIBLE (4625 1675);
FORCEPROP 0 LAST CDS_SEC 1
J 0
(4625 1675);
DISPLAY 1.021277 (4625 1675);
DISPLAY INVISIBLE (4625 1675);
FORCEADD Q_RES..1
(4325 1775);
FORCEPROP 1 LAST MATERIAL CHIP
J 0
(4450 1775);
DISPLAY 0.510638 (4450 1775);
PAINT SKYBLUE (4450 1775);
FORCEPROP 1 LAST VALUE 120
J 2
(4650 1775);
DISPLAY 0.510638 (4650 1775);
PAINT SKYBLUE (4650 1775);
FORCEPROP 1 LAST PART_NUMBER CS11202FB02
J 0
(4275 1875);
DISPLAY 0.510638 (4275 1875);
PAINT WHITE (4275 1875);
DISPLAY INVISIBLE (4275 1875);
FORCEPROP 1 LAST PACK_TYPE 0402LF
J 0
(4575 1625);
DISPLAY 0.510638 (4575 1625);
PAINT SKYBLUE (4575 1625);
DISPLAY INVISIBLE (4575 1625);
FORCEPROP 1 LAST WATTAGE 1/16W
J 2
(4300 1625);
DISPLAY 0.510638 (4300 1625);
PAINT SKYBLUE (4300 1625);
DISPLAY INVISIBLE (4300 1625);
FORCEPROP 1 LAST PATH I137
J 0
(4275 1925);
DISPLAY 0.978723 (4275 1925);
PAINT WHITE (4275 1925);
DISPLAY INVISIBLE (4275 1925);
FORCEPROP 1 LAST TOLERANCE 1%
J 0
(4325 1675);
DISPLAY 0.510638 (4325 1675);
PAINT SKYBLUE (4325 1675);
DISPLAY INVISIBLE (4325 1675);
FORCEPROP 2 LAST CDS_LIB pure_quanta
J 0
(4325 1775);
DISPLAY INVISIBLE (4325 1775);
FORCEPROP 1 LAST LOCATION R366
J 0
(4075 1775);
DISPLAY 0.702128 (4075 1775);
PAINT YELLOW (4075 1775);
FORCEPROP 1 LASTPIN (4225 1775) $PN 1
J 0
(4237 1787);
DISPLAY 0.808511 (4237 1787);
PAINT WHITE (4237 1787);
FORCEPROP 1 LASTPIN (4425 1775) $PN 2
J 0
(4387 1787);
DISPLAY 0.808511 (4387 1787);
PAINT WHITE (4387 1787);
FORCEPROP 0 LAST $SEC 1
J 0
(4625 1825);
DISPLAY 0.680851 (4625 1825);
PAINT MONO (4625 1825);
DISPLAY INVISIBLE (4625 1825);
FORCEPROP 0 LAST CDS_SEC 1
J 0
(4625 1825);
DISPLAY 1.021277 (4625 1825);
DISPLAY INVISIBLE (4625 1825);
FORCEADD Q_RES..1
(4325 1925);
FORCEPROP 1 LAST PART_NUMBER CS11202FB02
J 0
(4225 2100);
DISPLAY 0.510638 (4225 2100);
PAINT WHITE (4225 2100);
FORCEPROP 1 LAST PACK_TYPE 0402LF
J 0
(4125 2025);
DISPLAY 0.510638 (4125 2025);
PAINT SKYBLUE (4125 2025);
FORCEPROP 1 LAST MATERIAL CHIP
J 0
(4450 1925);
DISPLAY 0.510638 (4450 1925);
PAINT SKYBLUE (4450 1925);
FORCEPROP 1 LAST WATTAGE 1/16W
J 2
(4575 2025);
DISPLAY 0.510638 (4575 2025);
PAINT SKYBLUE (4575 2025);
FORCEPROP 1 LAST TOLERANCE 1%
J 0
(4625 2025);
DISPLAY 0.510638 (4625 2025);
PAINT SKYBLUE (4625 2025);
FORCEPROP 1 LAST VALUE 120
J 2
(4650 1925);
DISPLAY 0.510638 (4650 1925);
PAINT SKYBLUE (4650 1925);
FORCEPROP 1 LAST PATH I138
J 0
(4275 2075);
DISPLAY 0.978723 (4275 2075);
PAINT WHITE (4275 2075);
DISPLAY INVISIBLE (4275 2075);
FORCEPROP 2 LAST CDS_LIB pure_quanta
J 0
(4325 1925);
DISPLAY INVISIBLE (4325 1925);
FORCEPROP 1 LAST LOCATION R365
J 0
(4075 1925);
DISPLAY 0.702128 (4075 1925);
PAINT YELLOW (4075 1925);
FORCEPROP 1 LASTPIN (4225 1925) $PN 1
J 0
(4237 1937);
DISPLAY 0.808511 (4237 1937);
PAINT WHITE (4237 1937);
FORCEPROP 1 LASTPIN (4425 1925) $PN 2
J 0
(4387 1937);
DISPLAY 0.808511 (4387 1937);
PAINT WHITE (4387 1937);
FORCEPROP 0 LAST $SEC 1
J 0
(4625 1975);
DISPLAY 0.680851 (4625 1975);
PAINT MONO (4625 1975);
DISPLAY INVISIBLE (4625 1975);
FORCEPROP 0 LAST CDS_SEC 1
J 0
(4625 1975);
DISPLAY 1.021277 (4625 1975);
DISPLAY INVISIBLE (4625 1975);
FORCEADD UNIVERSAL_POWER..1
(4775 2125);
FORCEPROP 3 LASTPIN (4775 2075) SIG_NAME P1V2_AUX\g
J 0
(4785 2085);
DISPLAY 0.659574 (4785 2085);
PAINT MONO (4785 2085);
DISPLAY INVISIBLE (4785 2085);
FORCEPROP 1 LAST HDL_POWER P1V2_AUX
J 1
(4825 2175);
DISPLAY 0.702128 (4825 2175);
PAINT GREEN (4825 2175);
FORCEPROP 1 LAST PATH I139
J 0
(4825 2150);
DISPLAY 0.872340 (4825 2150);
PAINT AQUA (4825 2150);
DISPLAY INVISIBLE (4825 2150);
FORCEPROP 2 LAST CDS_LIB logical_power
J 0
(4775 2125);
DISPLAY INVISIBLE (4775 2125);
FORCEADD Q_RES..1
(-2425 -850);
FORCEPROP 1 LAST PART_NUMBER CS00002JB13
J 0
(-2225 -900);
DISPLAY 0.510638 (-2225 -900);
PAINT WHITE (-2225 -900);
FORCEPROP 1 LAST VALUE 0
J 2
(-2175 -850);
DISPLAY 0.510638 (-2175 -850);
PAINT SKYBLUE (-2175 -850);
FORCEPROP 1 LAST MATERIAL EMPTY
J 0
(-2225 -800);
DISPLAY 0.510638 (-2225 -800);
PAINT RED (-2225 -800);
FORCEPROP 1 LAST PACK_TYPE 0402LF
J 0
(-2175 -1000);
DISPLAY 0.510638 (-2175 -1000);
PAINT SKYBLUE (-2175 -1000);
DISPLAY INVISIBLE (-2175 -1000);
FORCEPROP 1 LAST WATTAGE 1/16W
J 2
(-2450 -1000);
DISPLAY 0.510638 (-2450 -1000);
PAINT SKYBLUE (-2450 -1000);
DISPLAY INVISIBLE (-2450 -1000);
FORCEPROP 1 LAST PATH I14
J 0
(-2475 -700);
DISPLAY 0.978723 (-2475 -700);
PAINT WHITE (-2475 -700);
DISPLAY INVISIBLE (-2475 -700);
FORCEPROP 1 LAST TOLERANCE 5%
J 0
(-2425 -950);
DISPLAY 0.510638 (-2425 -950);
PAINT SKYBLUE (-2425 -950);
DISPLAY INVISIBLE (-2425 -950);
FORCEPROP 2 LAST SEC_TYPE 0402LF
J 0
(-2475 -650);
DISPLAY 0.680851 (-2475 -650);
DISPLAY INVISIBLE (-2475 -650);
FORCEPROP 2 LAST CDS_LIB pure_quanta
J 0
(-2425 -850);
DISPLAY INVISIBLE (-2425 -850);
FORCEPROP 1 LAST LOCATION R1
J 0
(-2625 -850);
DISPLAY 0.702128 (-2625 -850);
PAINT YELLOW (-2625 -850);
FORCEPROP 1 LASTPIN (-2525 -850) $PN 1
J 0
(-2513 -838);
DISPLAY 0.808511 (-2513 -838);
PAINT WHITE (-2513 -838);
FORCEPROP 1 LASTPIN (-2325 -850) $PN 2
J 0
(-2363 -838);
DISPLAY 0.808511 (-2363 -838);
PAINT WHITE (-2363 -838);
FORCEPROP 2 LAST SEC 1
J 0
(-2475 -650);
DISPLAY 0.680851 (-2475 -650);
PAINT MONO (-2475 -650);
DISPLAY INVISIBLE (-2475 -650);
FORCEADD UNIVERSAL_POWER..1
(1150 2875);
FORCEPROP 3 LASTPIN (1150 2825) SIG_NAME P0V6_DDR_VREF_AUX\g
J 0
(1160 2835);
DISPLAY 0.659574 (1160 2835);
PAINT MONO (1160 2835);
DISPLAY INVISIBLE (1160 2835);
FORCEPROP 1 LAST HDL_POWER P0V6_DDR_VREF_AUX
J 1
(1000 2900);
DISPLAY 0.702128 (1000 2900);
PAINT GREEN (1000 2900);
FORCEPROP 2 LAST CDS_LIB logical_power
J 0
(1150 2875);
DISPLAY INVISIBLE (1150 2875);
FORCEPROP 1 LAST PATH I140
J 0
(1200 2900);
DISPLAY 0.872340 (1200 2900);
PAINT AQUA (1200 2900);
DISPLAY INVISIBLE (1200 2900);
FORCEADD Q_RES..2
(1400 2775);
FORCEPROP 1 LAST PACK_TYPE 0402LF
J 0
(1450 2700);
DISPLAY 0.510638 (1450 2700);
PAINT SKYBLUE (1450 2700);
FORCEPROP 1 LAST MATERIAL CHIP
J 0
(1425 2650);
DISPLAY 0.510638 (1425 2650);
PAINT SKYBLUE (1425 2650);
FORCEPROP 1 LAST WATTAGE 1/16W
J 0
(1440 2750);
DISPLAY 0.510638 (1440 2750);
PAINT SKYBLUE (1440 2750);
FORCEPROP 1 LAST TOLERANCE 1%
J 0
(1445 2800);
DISPLAY 0.510638 (1445 2800);
PAINT SKYBLUE (1445 2800);
FORCEPROP 1 LAST VALUE 1K
J 0
(1445 2850);
DISPLAY 0.510638 (1445 2850);
PAINT SKYBLUE (1445 2850);
FORCEPROP 1 LAST PART_NUMBER CS21002FB06
R 3
J 0
(1325 2925);
DISPLAY 0.510638 (1325 2925);
PAINT WHITE (1325 2925);
FORCEPROP 1 LAST PATH I141
J 0
(1450 2950);
DISPLAY 0.978723 (1450 2950);
PAINT WHITE (1450 2950);
DISPLAY INVISIBLE (1450 2950);
FORCEPROP 2 LAST SEC_TYPE 0402LF
J 0
(1450 3000);
DISPLAY 0.680851 (1450 3000);
DISPLAY INVISIBLE (1450 3000);
FORCEPROP 2 LAST CDS_LIB pure_quanta
J 0
(1400 2775);
DISPLAY INVISIBLE (1400 2775);
FORCEPROP 1 LAST LOCATION R4
J 0
(1445 2900);
DISPLAY 0.702128 (1445 2900);
PAINT YELLOW (1445 2900);
FORCEPROP 1 LASTPIN (1400 2875) $PN 1
J 0
(1405 2837);
DISPLAY 0.808511 (1405 2837);
PAINT WHITE (1405 2837);
FORCEPROP 1 LASTPIN (1400 2675) $PN 2
J 0
(1405 2685);
DISPLAY 0.808511 (1405 2685);
PAINT WHITE (1405 2685);
FORCEPROP 2 LAST SEC 1
J 0
(1450 3000);
DISPLAY 0.680851 (1450 3000);
PAINT MONO (1450 3000);
DISPLAY INVISIBLE (1450 3000);
FORCEADD Q_RES..2
(1750 2775);
FORCEPROP 1 LAST PACK_TYPE 0402LF
J 0
(1800 2650);
DISPLAY 0.510638 (1800 2650);
PAINT SKYBLUE (1800 2650);
FORCEPROP 1 LAST MATERIAL CHIP
J 0
(1790 2700);
DISPLAY 0.510638 (1790 2700);
PAINT SKYBLUE (1790 2700);
FORCEPROP 1 LAST WATTAGE 1/16W
J 0
(1790 2750);
DISPLAY 0.510638 (1790 2750);
PAINT SKYBLUE (1790 2750);
FORCEPROP 1 LAST TOLERANCE 1%
J 0
(1795 2800);
DISPLAY 0.510638 (1795 2800);
PAINT SKYBLUE (1795 2800);
FORCEPROP 1 LAST VALUE 1K
J 0
(1795 2850);
DISPLAY 0.510638 (1795 2850);
PAINT SKYBLUE (1795 2850);
FORCEPROP 1 LAST PART_NUMBER CS21002FB06
J 0
(1775 2650);
DISPLAY 0.510638 (1775 2650);
PAINT WHITE (1775 2650);
DISPLAY INVISIBLE (1775 2650);
FORCEPROP 1 LAST PATH I142
J 0
(1800 2950);
DISPLAY 0.978723 (1800 2950);
PAINT WHITE (1800 2950);
DISPLAY INVISIBLE (1800 2950);
FORCEPROP 2 LAST CDS_LIB pure_quanta
J 0
(1750 2775);
DISPLAY INVISIBLE (1750 2775);
FORCEPROP 2 LAST SEC_TYPE 0402LF
J 0
(1800 3000);
DISPLAY 0.680851 (1800 3000);
DISPLAY INVISIBLE (1800 3000);
FORCEPROP 1 LAST LOCATION R5
J 0
(1795 2900);
DISPLAY 0.702128 (1795 2900);
PAINT YELLOW (1795 2900);
FORCEPROP 1 LASTPIN (1750 2875) $PN 1
J 0
(1755 2837);
DISPLAY 0.808511 (1755 2837);
PAINT WHITE (1755 2837);
FORCEPROP 1 LASTPIN (1750 2675) $PN 2
J 0
(1755 2685);
DISPLAY 0.808511 (1755 2685);
PAINT WHITE (1755 2685);
FORCEPROP 2 LAST SEC 1
J 0
(1800 3000);
DISPLAY 0.680851 (1800 3000);
PAINT MONO (1800 3000);
DISPLAY INVISIBLE (1800 3000);
FORCEADD Q_RES..2
(2075 2775);
FORCEPROP 1 LAST PACK_TYPE 0402LF
J 0
(2120 2575);
DISPLAY 0.510638 (2120 2575);
PAINT SKYBLUE (2120 2575);
FORCEPROP 1 LAST MATERIAL CHIP
J 0
(2120 2675);
DISPLAY 0.510638 (2120 2675);
PAINT SKYBLUE (2120 2675);
FORCEPROP 1 LAST VALUE 240
J 0
(2125 2825);
DISPLAY 0.510638 (2125 2825);
PAINT SKYBLUE (2125 2825);
FORCEPROP 1 LAST TOLERANCE 1%
J 0
(2130 2775);
DISPLAY 0.510638 (2130 2775);
PAINT SKYBLUE (2130 2775);
FORCEPROP 1 LAST WATTAGE 1/16W
J 0
(2120 2725);
DISPLAY 0.510638 (2120 2725);
PAINT SKYBLUE (2120 2725);
FORCEPROP 1 LAST PART_NUMBER CS12402FB01
J 0
(2120 2625);
DISPLAY 0.510638 (2120 2625);
PAINT WHITE (2120 2625);
FORCEPROP 1 LAST PATH I143
J 0
(2125 2950);
DISPLAY 0.978723 (2125 2950);
PAINT WHITE (2125 2950);
DISPLAY INVISIBLE (2125 2950);
FORCEPROP 2 LAST CDS_LIB pure_quanta
J 0
(2075 2775);
DISPLAY INVISIBLE (2075 2775);
FORCEPROP 2 LAST SEC_TYPE 0402LF
J 0
(2125 3000);
DISPLAY 0.680851 (2125 3000);
DISPLAY INVISIBLE (2125 3000);
FORCEPROP 1 LAST LOCATION R6
J 0
(2125 2875);
DISPLAY 0.702128 (2125 2875);
PAINT YELLOW (2125 2875);
FORCEPROP 1 LASTPIN (2075 2875) $PN 1
J 0
(2080 2837);
DISPLAY 0.808511 (2080 2837);
PAINT WHITE (2080 2837);
FORCEPROP 1 LASTPIN (2075 2675) $PN 2
J 0
(2080 2685);
DISPLAY 0.808511 (2080 2685);
PAINT WHITE (2080 2685);
FORCEPROP 2 LAST SEC 1
J 0
(2125 3000);
DISPLAY 0.680851 (2125 3000);
PAINT MONO (2125 3000);
DISPLAY INVISIBLE (2125 3000);
FORCEADD TAP..1
R 2
(2675 2775);
FORCEPROP 3 LASTPIN (2725 2775) SIG_NAME M_BMC_DDR4_MA<13>
J 0
(2735 2785);
DISPLAY 0.659574 (2735 2785);
PAINT MONO (2735 2785);
DISPLAY INVISIBLE (2735 2785);
FORCEPROP 1 LASTPIN (2725 2775) BN 13
J 2
(2737 2783);
DISPLAY 0.680851 (2737 2783);
PAINT MONO (2737 2783);
FORCEPROP 1 LAST PATH I144
J 2
(2677 2775);
DISPLAY 0.872340 (2677 2775);
PAINT GREEN (2677 2775);
DISPLAY INVISIBLE (2677 2775);
FORCEPROP 1 LAST HDL_TAP TRUE
J 2
(2350 2650);
DISPLAY 0.872340 (2350 2650);
DISPLAY INVISIBLE (2350 2650);
FORCEPROP 1 LAST BODY_TYPE PLUMBING
J 2
(2675 2825);
DISPLAY 0.872340 (2675 2825);
PAINT GREEN (2675 2825);
DISPLAY INVISIBLE (2675 2825);
FORCEPROP 2 LAST CDS_LIB standard
J 0
(2675 2775);
DISPLAY INVISIBLE (2675 2775);
FORCEADD TAP..1
R 2
(2675 2925);
FORCEPROP 3 LASTPIN (2725 2925) SIG_NAME M_BMC_DDR4_MA<12>
J 0
(2735 2935);
DISPLAY 0.659574 (2735 2935);
PAINT MONO (2735 2935);
DISPLAY INVISIBLE (2735 2935);
FORCEPROP 1 LASTPIN (2725 2925) BN 12
J 2
(2737 2933);
DISPLAY 0.680851 (2737 2933);
PAINT MONO (2737 2933);
FORCEPROP 1 LAST PATH I145
J 2
(2677 2925);
DISPLAY 0.872340 (2677 2925);
PAINT GREEN (2677 2925);
DISPLAY INVISIBLE (2677 2925);
FORCEPROP 1 LAST HDL_TAP TRUE
J 2
(2350 2800);
DISPLAY 0.872340 (2350 2800);
DISPLAY INVISIBLE (2350 2800);
FORCEPROP 1 LAST BODY_TYPE PLUMBING
J 2
(2675 2975);
DISPLAY 0.872340 (2675 2975);
PAINT GREEN (2675 2975);
DISPLAY INVISIBLE (2675 2975);
FORCEPROP 2 LAST CDS_LIB standard
J 0
(2675 2925);
DISPLAY INVISIBLE (2675 2925);
FORCEADD TAP..1
R 2
(2675 3375);
FORCEPROP 3 LASTPIN (2725 3375) SIG_NAME M_BMC_DDR4_MA<9>
J 0
(2735 3385);
DISPLAY 0.659574 (2735 3385);
PAINT MONO (2735 3385);
DISPLAY INVISIBLE (2735 3385);
FORCEPROP 1 LASTPIN (2725 3375) BN 9
J 2
(2737 3383);
DISPLAY 0.680851 (2737 3383);
PAINT MONO (2737 3383);
FORCEPROP 1 LAST PATH I146
J 2
(2677 3375);
DISPLAY 0.872340 (2677 3375);
PAINT GREEN (2677 3375);
DISPLAY INVISIBLE (2677 3375);
FORCEPROP 1 LAST HDL_TAP TRUE
J 2
(2350 3250);
DISPLAY 0.872340 (2350 3250);
DISPLAY INVISIBLE (2350 3250);
FORCEPROP 1 LAST BODY_TYPE PLUMBING
J 2
(2675 3425);
DISPLAY 0.872340 (2675 3425);
PAINT GREEN (2675 3425);
DISPLAY INVISIBLE (2675 3425);
FORCEPROP 2 LAST CDS_LIB standard
J 0
(2675 3375);
DISPLAY INVISIBLE (2675 3375);
FORCEADD TAP..1
R 2
(2675 3225);
FORCEPROP 3 LASTPIN (2725 3225) SIG_NAME M_BMC_DDR4_MA<10>
J 0
(2735 3235);
DISPLAY 0.659574 (2735 3235);
PAINT MONO (2735 3235);
DISPLAY INVISIBLE (2735 3235);
FORCEPROP 1 LASTPIN (2725 3225) BN 10
J 2
(2737 3233);
DISPLAY 0.680851 (2737 3233);
PAINT MONO (2737 3233);
FORCEPROP 1 LAST PATH I147
J 2
(2677 3225);
DISPLAY 0.872340 (2677 3225);
PAINT GREEN (2677 3225);
DISPLAY INVISIBLE (2677 3225);
FORCEPROP 1 LAST HDL_TAP TRUE
J 2
(2350 3100);
DISPLAY 0.872340 (2350 3100);
DISPLAY INVISIBLE (2350 3100);
FORCEPROP 1 LAST BODY_TYPE PLUMBING
J 2
(2675 3275);
DISPLAY 0.872340 (2675 3275);
PAINT GREEN (2675 3275);
DISPLAY INVISIBLE (2675 3275);
FORCEPROP 2 LAST CDS_LIB standard
J 0
(2675 3225);
DISPLAY INVISIBLE (2675 3225);
FORCEADD TAP..1
R 2
(2675 3075);
FORCEPROP 3 LASTPIN (2725 3075) SIG_NAME M_BMC_DDR4_MA<11>
J 0
(2735 3085);
DISPLAY 0.659574 (2735 3085);
PAINT MONO (2735 3085);
DISPLAY INVISIBLE (2735 3085);
FORCEPROP 1 LASTPIN (2725 3075) BN 11
J 2
(2737 3083);
DISPLAY 0.680851 (2737 3083);
PAINT MONO (2737 3083);
FORCEPROP 1 LAST PATH I148
J 2
(2677 3075);
DISPLAY 0.872340 (2677 3075);
PAINT GREEN (2677 3075);
DISPLAY INVISIBLE (2677 3075);
FORCEPROP 1 LAST HDL_TAP TRUE
J 2
(2350 2950);
DISPLAY 0.872340 (2350 2950);
DISPLAY INVISIBLE (2350 2950);
FORCEPROP 1 LAST BODY_TYPE PLUMBING
J 2
(2675 3125);
DISPLAY 0.872340 (2675 3125);
PAINT GREEN (2675 3125);
DISPLAY INVISIBLE (2675 3125);
FORCEPROP 2 LAST CDS_LIB standard
J 0
(2675 3075);
DISPLAY INVISIBLE (2675 3075);
FORCEADD TAP..1
R 2
(2675 3825);
FORCEPROP 3 LASTPIN (2725 3825) SIG_NAME M_BMC_DDR4_MA<6>
J 0
(2735 3835);
DISPLAY 0.659574 (2735 3835);
PAINT MONO (2735 3835);
DISPLAY INVISIBLE (2735 3835);
FORCEPROP 1 LASTPIN (2725 3825) BN 6
J 2
(2737 3833);
DISPLAY 0.680851 (2737 3833);
PAINT MONO (2737 3833);
FORCEPROP 1 LAST PATH I149
J 2
(2677 3825);
DISPLAY 0.872340 (2677 3825);
PAINT GREEN (2677 3825);
DISPLAY INVISIBLE (2677 3825);
FORCEPROP 1 LAST HDL_TAP TRUE
J 2
(2350 3700);
DISPLAY 0.872340 (2350 3700);
DISPLAY INVISIBLE (2350 3700);
FORCEPROP 1 LAST BODY_TYPE PLUMBING
J 2
(2675 3875);
DISPLAY 0.872340 (2675 3875);
PAINT GREEN (2675 3875);
DISPLAY INVISIBLE (2675 3875);
FORCEPROP 2 LAST CDS_LIB standard
J 0
(2675 3825);
DISPLAY INVISIBLE (2675 3825);
FORCEADD UNIVERSAL_GND..1
(-2025 -1200);
FORCEPROP 3 LASTPIN (-2025 -1150) SIG_NAME GND\g
J 0
(-2015 -1140);
DISPLAY 0.659574 (-2015 -1140);
PAINT MONO (-2015 -1140);
DISPLAY INVISIBLE (-2015 -1140);
FORCEPROP 1 LAST PATH I15
J 0
(-1950 -1200);
DISPLAY 0.872340 (-1950 -1200);
PAINT AQUA (-1950 -1200);
DISPLAY INVISIBLE (-1950 -1200);
FORCEPROP 1 LAST HDL_POWER GND
J 1
(-2000 -1275);
DISPLAY 0.702128 (-2000 -1275);
PAINT GREEN (-2000 -1275);
DISPLAY INVISIBLE (-2000 -1275);
FORCEPROP 2 LAST CDS_LIB logical_power
J 0
(-2025 -1200);
DISPLAY INVISIBLE (-2025 -1200);
FORCEADD TAP..1
R 2
(2675 3525);
FORCEPROP 3 LASTPIN (2725 3525) SIG_NAME M_BMC_DDR4_MA<8>
J 0
(2735 3535);
DISPLAY 0.659574 (2735 3535);
PAINT MONO (2735 3535);
DISPLAY INVISIBLE (2735 3535);
FORCEPROP 1 LASTPIN (2725 3525) BN 8
J 2
(2737 3533);
DISPLAY 0.680851 (2737 3533);
PAINT MONO (2737 3533);
FORCEPROP 1 LAST PATH I150
J 2
(2677 3525);
DISPLAY 0.872340 (2677 3525);
PAINT GREEN (2677 3525);
DISPLAY INVISIBLE (2677 3525);
FORCEPROP 1 LAST HDL_TAP TRUE
J 2
(2350 3400);
DISPLAY 0.872340 (2350 3400);
DISPLAY INVISIBLE (2350 3400);
FORCEPROP 1 LAST BODY_TYPE PLUMBING
J 2
(2675 3575);
DISPLAY 0.872340 (2675 3575);
PAINT GREEN (2675 3575);
DISPLAY INVISIBLE (2675 3575);
FORCEPROP 2 LAST CDS_LIB standard
J 0
(2675 3525);
DISPLAY INVISIBLE (2675 3525);
FORCEADD TAP..1
R 2
(2675 3675);
FORCEPROP 3 LASTPIN (2725 3675) SIG_NAME M_BMC_DDR4_MA<7>
J 0
(2735 3685);
DISPLAY 0.659574 (2735 3685);
PAINT MONO (2735 3685);
DISPLAY INVISIBLE (2735 3685);
FORCEPROP 1 LASTPIN (2725 3675) BN 7
J 2
(2737 3683);
DISPLAY 0.680851 (2737 3683);
PAINT MONO (2737 3683);
FORCEPROP 1 LAST PATH I151
J 2
(2677 3675);
DISPLAY 0.872340 (2677 3675);
PAINT GREEN (2677 3675);
DISPLAY INVISIBLE (2677 3675);
FORCEPROP 1 LAST HDL_TAP TRUE
J 2
(2350 3550);
DISPLAY 0.872340 (2350 3550);
DISPLAY INVISIBLE (2350 3550);
FORCEPROP 1 LAST BODY_TYPE PLUMBING
J 2
(2675 3725);
DISPLAY 0.872340 (2675 3725);
PAINT GREEN (2675 3725);
DISPLAY INVISIBLE (2675 3725);
FORCEPROP 2 LAST CDS_LIB standard
J 0
(2675 3675);
DISPLAY INVISIBLE (2675 3675);
FORCEADD TAP..1
R 2
(2675 3975);
FORCEPROP 3 LASTPIN (2725 3975) SIG_NAME M_BMC_DDR4_MA<5>
J 0
(2735 3985);
DISPLAY 0.659574 (2735 3985);
PAINT MONO (2735 3985);
DISPLAY INVISIBLE (2735 3985);
FORCEPROP 1 LASTPIN (2725 3975) BN 5
J 2
(2737 3983);
DISPLAY 0.680851 (2737 3983);
PAINT MONO (2737 3983);
FORCEPROP 1 LAST PATH I152
J 2
(2677 3975);
DISPLAY 0.872340 (2677 3975);
PAINT GREEN (2677 3975);
DISPLAY INVISIBLE (2677 3975);
FORCEPROP 1 LAST HDL_TAP TRUE
J 2
(2350 3850);
DISPLAY 0.872340 (2350 3850);
DISPLAY INVISIBLE (2350 3850);
FORCEPROP 1 LAST BODY_TYPE PLUMBING
J 2
(2675 4025);
DISPLAY 0.872340 (2675 4025);
PAINT GREEN (2675 4025);
DISPLAY INVISIBLE (2675 4025);
FORCEPROP 2 LAST CDS_LIB standard
J 0
(2675 3975);
DISPLAY INVISIBLE (2675 3975);
FORCEADD TAP..1
R 2
(2675 4425);
FORCEPROP 3 LASTPIN (2725 4425) SIG_NAME M_BMC_DDR4_MA<2>
J 0
(2735 4435);
DISPLAY 0.659574 (2735 4435);
PAINT MONO (2735 4435);
DISPLAY INVISIBLE (2735 4435);
FORCEPROP 1 LASTPIN (2725 4425) BN 2
J 2
(2737 4433);
DISPLAY 0.680851 (2737 4433);
PAINT MONO (2737 4433);
FORCEPROP 1 LAST PATH I153
J 2
(2677 4425);
DISPLAY 0.872340 (2677 4425);
PAINT GREEN (2677 4425);
DISPLAY INVISIBLE (2677 4425);
FORCEPROP 1 LAST HDL_TAP TRUE
J 2
(2350 4300);
DISPLAY 0.872340 (2350 4300);
DISPLAY INVISIBLE (2350 4300);
FORCEPROP 1 LAST BODY_TYPE PLUMBING
J 2
(2675 4475);
DISPLAY 0.872340 (2675 4475);
PAINT GREEN (2675 4475);
DISPLAY INVISIBLE (2675 4475);
FORCEPROP 2 LAST CDS_LIB standard
J 0
(2675 4425);
DISPLAY INVISIBLE (2675 4425);
FORCEADD TAP..1
R 2
(2675 4275);
FORCEPROP 3 LASTPIN (2725 4275) SIG_NAME M_BMC_DDR4_MA<3>
J 0
(2735 4285);
DISPLAY 0.659574 (2735 4285);
PAINT MONO (2735 4285);
DISPLAY INVISIBLE (2735 4285);
FORCEPROP 1 LASTPIN (2725 4275) BN 3
J 2
(2737 4283);
DISPLAY 0.680851 (2737 4283);
PAINT MONO (2737 4283);
FORCEPROP 1 LAST PATH I154
J 2
(2677 4275);
DISPLAY 0.872340 (2677 4275);
PAINT GREEN (2677 4275);
DISPLAY INVISIBLE (2677 4275);
FORCEPROP 1 LAST HDL_TAP TRUE
J 2
(2350 4150);
DISPLAY 0.872340 (2350 4150);
DISPLAY INVISIBLE (2350 4150);
FORCEPROP 1 LAST BODY_TYPE PLUMBING
J 2
(2675 4325);
DISPLAY 0.872340 (2675 4325);
PAINT GREEN (2675 4325);
DISPLAY INVISIBLE (2675 4325);
FORCEPROP 2 LAST CDS_LIB standard
J 0
(2675 4275);
DISPLAY INVISIBLE (2675 4275);
FORCEADD TAP..1
R 2
(2675 4125);
FORCEPROP 3 LASTPIN (2725 4125) SIG_NAME M_BMC_DDR4_MA<4>
J 0
(2735 4135);
DISPLAY 0.659574 (2735 4135);
PAINT MONO (2735 4135);
DISPLAY INVISIBLE (2735 4135);
FORCEPROP 1 LASTPIN (2725 4125) BN 4
J 2
(2737 4133);
DISPLAY 0.680851 (2737 4133);
PAINT MONO (2737 4133);
FORCEPROP 1 LAST PATH I155
J 2
(2677 4125);
DISPLAY 0.872340 (2677 4125);
PAINT GREEN (2677 4125);
DISPLAY INVISIBLE (2677 4125);
FORCEPROP 1 LAST HDL_TAP TRUE
J 2
(2350 4000);
DISPLAY 0.872340 (2350 4000);
DISPLAY INVISIBLE (2350 4000);
FORCEPROP 1 LAST BODY_TYPE PLUMBING
J 2
(2675 4175);
DISPLAY 0.872340 (2675 4175);
PAINT GREEN (2675 4175);
DISPLAY INVISIBLE (2675 4175);
FORCEPROP 2 LAST CDS_LIB standard
J 0
(2675 4125);
DISPLAY INVISIBLE (2675 4125);
FORCEADD OFFPAGE..3
R 2
(1625 4825);
FORCEPROP 2 LAST $XR1 20 
J 0
(1286 4825);
DISPLAY 0.638298 (1286 4825);
PAINT MONO (1286 4825);
FORCEPROP 2 LAST $XR0 12 
J 0
(1376 4825);
DISPLAY 0.638298 (1376 4825);
PAINT MONO (1376 4825);
FORCEPROP 2 LAST PATH I156
J 0
(1425 4875);
DISPLAY 1.021277 (1425 4875);
DISPLAY INVISIBLE (1425 4875);
FORCEPROP 1 LAST COMMENT_BODY TRUE
J 2
(1675 4725);
DISPLAY 0.872340 (1675 4725);
PAINT PEACH (1675 4725);
DISPLAY INVISIBLE (1675 4725);
FORCEPROP 1 LAST OFFPAGE TRUE
J 2
(1300 4700);
DISPLAY 0.872340 (1300 4700);
PAINT GREEN (1300 4700);
DISPLAY INVISIBLE (1300 4700);
FORCEPROP 2 LAST CDS_LIB standard
J 0
(1625 4825);
DISPLAY INVISIBLE (1625 4825);
FORCEADD TAP..1
R 2
(2675 4575);
FORCEPROP 3 LASTPIN (2725 4575) SIG_NAME M_BMC_DDR4_MA<1>
J 0
(2735 4585);
DISPLAY 0.659574 (2735 4585);
PAINT MONO (2735 4585);
DISPLAY INVISIBLE (2735 4585);
FORCEPROP 1 LASTPIN (2725 4575) BN 1
J 2
(2737 4583);
DISPLAY 0.680851 (2737 4583);
PAINT MONO (2737 4583);
FORCEPROP 1 LAST PATH I157
J 2
(2677 4575);
DISPLAY 0.872340 (2677 4575);
PAINT GREEN (2677 4575);
DISPLAY INVISIBLE (2677 4575);
FORCEPROP 1 LAST HDL_TAP TRUE
J 2
(2350 4450);
DISPLAY 0.872340 (2350 4450);
DISPLAY INVISIBLE (2350 4450);
FORCEPROP 1 LAST BODY_TYPE PLUMBING
J 2
(2675 4625);
DISPLAY 0.872340 (2675 4625);
PAINT GREEN (2675 4625);
DISPLAY INVISIBLE (2675 4625);
FORCEPROP 2 LAST CDS_LIB standard
J 0
(2675 4575);
DISPLAY INVISIBLE (2675 4575);
FORCEADD TAP..1
R 2
(2675 4725);
FORCEPROP 3 LASTPIN (2725 4725) SIG_NAME M_BMC_DDR4_MA<0>
J 0
(2735 4735);
DISPLAY 0.659574 (2735 4735);
PAINT MONO (2735 4735);
DISPLAY INVISIBLE (2735 4735);
FORCEPROP 1 LASTPIN (2725 4725) BN 0
J 2
(2737 4733);
DISPLAY 0.680851 (2737 4733);
PAINT MONO (2737 4733);
FORCEPROP 1 LAST PATH I158
J 2
(2677 4725);
DISPLAY 0.872340 (2677 4725);
PAINT GREEN (2677 4725);
DISPLAY INVISIBLE (2677 4725);
FORCEPROP 1 LAST HDL_TAP TRUE
J 2
(2350 4600);
DISPLAY 0.872340 (2350 4600);
DISPLAY INVISIBLE (2350 4600);
FORCEPROP 1 LAST BODY_TYPE PLUMBING
J 2
(2675 4775);
DISPLAY 0.872340 (2675 4775);
PAINT GREEN (2675 4775);
DISPLAY INVISIBLE (2675 4775);
FORCEPROP 2 LAST CDS_LIB standard
J 0
(2675 4725);
DISPLAY INVISIBLE (2675 4725);
FORCEADD Q_RES..1
(3600 2700);
FORCEPROP 1 LAST MATERIAL CHIP
J 0
(3725 2700);
DISPLAY 0.510638 (3725 2700);
PAINT SKYBLUE (3725 2700);
FORCEPROP 1 LAST VALUE 120
J 2
(3925 2700);
DISPLAY 0.510638 (3925 2700);
PAINT SKYBLUE (3925 2700);
FORCEPROP 1 LAST PART_NUMBER CS11202FB02
J 0
(4275 2700);
DISPLAY 0.510638 (4275 2700);
PAINT WHITE (4275 2700);
DISPLAY INVISIBLE (4275 2700);
FORCEPROP 1 LAST PACK_TYPE 0402LF
J 0
(3850 2550);
DISPLAY 0.510638 (3850 2550);
PAINT SKYBLUE (3850 2550);
DISPLAY INVISIBLE (3850 2550);
FORCEPROP 1 LAST WATTAGE 1/16W
J 2
(3575 2550);
DISPLAY 0.510638 (3575 2550);
PAINT SKYBLUE (3575 2550);
DISPLAY INVISIBLE (3575 2550);
FORCEPROP 1 LAST PATH I159
J 0
(3550 2850);
DISPLAY 0.978723 (3550 2850);
PAINT WHITE (3550 2850);
DISPLAY INVISIBLE (3550 2850);
FORCEPROP 1 LAST TOLERANCE 1%
J 0
(3600 2600);
DISPLAY 0.510638 (3600 2600);
PAINT SKYBLUE (3600 2600);
DISPLAY INVISIBLE (3600 2600);
FORCEPROP 2 LAST CDS_LIB pure_quanta
J 0
(3600 2700);
DISPLAY INVISIBLE (3600 2700);
FORCEPROP 1 LAST LOCATION R339
J 0
(3375 2700);
DISPLAY 0.702128 (3375 2700);
PAINT YELLOW (3375 2700);
FORCEPROP 1 LASTPIN (3500 2700) $PN 1
J 0
(3512 2712);
DISPLAY 0.808511 (3512 2712);
PAINT WHITE (3512 2712);
FORCEPROP 1 LASTPIN (3700 2700) $PN 2
J 0
(3662 2712);
DISPLAY 0.808511 (3662 2712);
PAINT WHITE (3662 2712);
FORCEPROP 0 LAST $SEC 1
J 0
(3900 2750);
DISPLAY 0.680851 (3900 2750);
PAINT MONO (3900 2750);
DISPLAY INVISIBLE (3900 2750);
FORCEPROP 0 LAST CDS_SEC 1
J 0
(3900 2750);
DISPLAY 1.021277 (3900 2750);
DISPLAY INVISIBLE (3900 2750);
FORCEADD UNIVERSAL_GND..1
(-1950 -600);
FORCEPROP 3 LASTPIN (-1950 -550) SIG_NAME GND\g
J 0
(-1940 -540);
DISPLAY 0.659574 (-1940 -540);
PAINT MONO (-1940 -540);
DISPLAY INVISIBLE (-1940 -540);
FORCEPROP 1 LAST PATH I16
J 0
(-1875 -600);
DISPLAY 0.872340 (-1875 -600);
PAINT AQUA (-1875 -600);
DISPLAY INVISIBLE (-1875 -600);
FORCEPROP 1 LAST HDL_POWER GND
J 1
(-1925 -675);
DISPLAY 0.702128 (-1925 -675);
PAINT GREEN (-1925 -675);
DISPLAY INVISIBLE (-1925 -675);
FORCEPROP 2 LAST CDS_LIB logical_power
J 0
(-1950 -600);
DISPLAY INVISIBLE (-1950 -600);
FORCEADD Q_RES..1
(3600 2850);
FORCEPROP 1 LAST MATERIAL CHIP
J 0
(3725 2850);
DISPLAY 0.510638 (3725 2850);
PAINT SKYBLUE (3725 2850);
FORCEPROP 1 LAST VALUE 120
J 2
(3925 2850);
DISPLAY 0.510638 (3925 2850);
PAINT SKYBLUE (3925 2850);
FORCEPROP 1 LAST PART_NUMBER CS11202FB02
J 0
(4275 2850);
DISPLAY 0.510638 (4275 2850);
PAINT WHITE (4275 2850);
DISPLAY INVISIBLE (4275 2850);
FORCEPROP 1 LAST PACK_TYPE 0402LF
J 0
(3850 2700);
DISPLAY 0.510638 (3850 2700);
PAINT SKYBLUE (3850 2700);
DISPLAY INVISIBLE (3850 2700);
FORCEPROP 1 LAST WATTAGE 1/16W
J 2
(3575 2700);
DISPLAY 0.510638 (3575 2700);
PAINT SKYBLUE (3575 2700);
DISPLAY INVISIBLE (3575 2700);
FORCEPROP 1 LAST PATH I160
J 0
(3550 3000);
DISPLAY 0.978723 (3550 3000);
PAINT WHITE (3550 3000);
DISPLAY INVISIBLE (3550 3000);
FORCEPROP 1 LAST TOLERANCE 1%
J 0
(3600 2750);
DISPLAY 0.510638 (3600 2750);
PAINT SKYBLUE (3600 2750);
DISPLAY INVISIBLE (3600 2750);
FORCEPROP 2 LAST CDS_LIB pure_quanta
J 0
(3600 2850);
DISPLAY INVISIBLE (3600 2850);
FORCEPROP 1 LAST LOCATION R338
J 0
(3375 2850);
DISPLAY 0.702128 (3375 2850);
PAINT YELLOW (3375 2850);
FORCEPROP 1 LASTPIN (3500 2850) $PN 1
J 0
(3512 2862);
DISPLAY 0.808511 (3512 2862);
PAINT WHITE (3512 2862);
FORCEPROP 1 LASTPIN (3700 2850) $PN 2
J 0
(3662 2862);
DISPLAY 0.808511 (3662 2862);
PAINT WHITE (3662 2862);
FORCEPROP 0 LAST $SEC 1
J 0
(3900 2900);
DISPLAY 0.680851 (3900 2900);
PAINT MONO (3900 2900);
DISPLAY INVISIBLE (3900 2900);
FORCEPROP 0 LAST CDS_SEC 1
J 0
(3900 2900);
DISPLAY 1.021277 (3900 2900);
DISPLAY INVISIBLE (3900 2900);
FORCEADD Q_RES..1
(3600 3000);
FORCEPROP 1 LAST VALUE 120
J 2
(3925 3000);
DISPLAY 0.510638 (3925 3000);
PAINT SKYBLUE (3925 3000);
FORCEPROP 1 LAST MATERIAL CHIP
J 0
(3725 3000);
DISPLAY 0.510638 (3725 3000);
PAINT SKYBLUE (3725 3000);
FORCEPROP 1 LAST PART_NUMBER CS11202FB02
J 0
(4275 3000);
DISPLAY 0.510638 (4275 3000);
PAINT WHITE (4275 3000);
DISPLAY INVISIBLE (4275 3000);
FORCEPROP 1 LAST PACK_TYPE 0402LF
J 0
(3850 2850);
DISPLAY 0.510638 (3850 2850);
PAINT SKYBLUE (3850 2850);
DISPLAY INVISIBLE (3850 2850);
FORCEPROP 1 LAST WATTAGE 1/16W
J 2
(3575 2850);
DISPLAY 0.510638 (3575 2850);
PAINT SKYBLUE (3575 2850);
DISPLAY INVISIBLE (3575 2850);
FORCEPROP 1 LAST PATH I161
J 0
(3550 3150);
DISPLAY 0.978723 (3550 3150);
PAINT WHITE (3550 3150);
DISPLAY INVISIBLE (3550 3150);
FORCEPROP 1 LAST TOLERANCE 1%
J 0
(3600 2900);
DISPLAY 0.510638 (3600 2900);
PAINT SKYBLUE (3600 2900);
DISPLAY INVISIBLE (3600 2900);
FORCEPROP 2 LAST CDS_LIB pure_quanta
J 0
(3600 3000);
DISPLAY INVISIBLE (3600 3000);
FORCEPROP 1 LAST LOCATION R337
J 0
(3375 3000);
DISPLAY 0.702128 (3375 3000);
PAINT YELLOW (3375 3000);
FORCEPROP 1 LASTPIN (3500 3000) $PN 1
J 0
(3512 3012);
DISPLAY 0.808511 (3512 3012);
PAINT WHITE (3512 3012);
FORCEPROP 1 LASTPIN (3700 3000) $PN 2
J 0
(3662 3012);
DISPLAY 0.808511 (3662 3012);
PAINT WHITE (3662 3012);
FORCEPROP 0 LAST $SEC 1
J 0
(3900 3050);
DISPLAY 0.680851 (3900 3050);
PAINT MONO (3900 3050);
DISPLAY INVISIBLE (3900 3050);
FORCEPROP 0 LAST CDS_SEC 1
J 0
(3900 3050);
DISPLAY 1.021277 (3900 3050);
DISPLAY INVISIBLE (3900 3050);
FORCEADD Q_RES..1
(3600 3150);
FORCEPROP 1 LAST MATERIAL CHIP
J 0
(3725 3150);
DISPLAY 0.510638 (3725 3150);
PAINT SKYBLUE (3725 3150);
FORCEPROP 1 LAST VALUE 120
J 2
(3925 3150);
DISPLAY 0.510638 (3925 3150);
PAINT SKYBLUE (3925 3150);
FORCEPROP 1 LAST PART_NUMBER CS11202FB02
J 0
(4275 3325);
DISPLAY 0.510638 (4275 3325);
PAINT WHITE (4275 3325);
DISPLAY INVISIBLE (4275 3325);
FORCEPROP 1 LAST PACK_TYPE 0402LF
J 0
(3850 3000);
DISPLAY 0.510638 (3850 3000);
PAINT SKYBLUE (3850 3000);
DISPLAY INVISIBLE (3850 3000);
FORCEPROP 1 LAST WATTAGE 1/16W
J 2
(3575 3000);
DISPLAY 0.510638 (3575 3000);
PAINT SKYBLUE (3575 3000);
DISPLAY INVISIBLE (3575 3000);
FORCEPROP 1 LAST PATH I162
J 0
(3550 3300);
DISPLAY 0.978723 (3550 3300);
PAINT WHITE (3550 3300);
DISPLAY INVISIBLE (3550 3300);
FORCEPROP 1 LAST TOLERANCE 1%
J 0
(3600 3050);
DISPLAY 0.510638 (3600 3050);
PAINT SKYBLUE (3600 3050);
DISPLAY INVISIBLE (3600 3050);
FORCEPROP 2 LAST CDS_LIB pure_quanta
J 0
(3600 3150);
DISPLAY INVISIBLE (3600 3150);
FORCEPROP 1 LAST LOCATION R336
J 0
(3375 3150);
DISPLAY 0.702128 (3375 3150);
PAINT YELLOW (3375 3150);
FORCEPROP 1 LASTPIN (3500 3150) $PN 1
J 0
(3512 3162);
DISPLAY 0.808511 (3512 3162);
PAINT WHITE (3512 3162);
FORCEPROP 1 LASTPIN (3700 3150) $PN 2
J 0
(3662 3162);
DISPLAY 0.808511 (3662 3162);
PAINT WHITE (3662 3162);
FORCEPROP 0 LAST $SEC 1
J 0
(3900 3200);
DISPLAY 0.680851 (3900 3200);
PAINT MONO (3900 3200);
DISPLAY INVISIBLE (3900 3200);
FORCEPROP 0 LAST CDS_SEC 1
J 0
(3900 3200);
DISPLAY 1.021277 (3900 3200);
DISPLAY INVISIBLE (3900 3200);
FORCEADD Q_RES..1
(3600 3300);
FORCEPROP 1 LAST MATERIAL CHIP
J 0
(3725 3300);
DISPLAY 0.510638 (3725 3300);
PAINT SKYBLUE (3725 3300);
FORCEPROP 1 LAST VALUE 120
J 2
(3925 3300);
DISPLAY 0.510638 (3925 3300);
PAINT SKYBLUE (3925 3300);
FORCEPROP 1 LAST PART_NUMBER CS11202FB02
J 0
(4275 3350);
DISPLAY 0.510638 (4275 3350);
PAINT WHITE (4275 3350);
DISPLAY INVISIBLE (4275 3350);
FORCEPROP 1 LAST PACK_TYPE 0402LF
J 0
(3850 3150);
DISPLAY 0.510638 (3850 3150);
PAINT SKYBLUE (3850 3150);
DISPLAY INVISIBLE (3850 3150);
FORCEPROP 1 LAST WATTAGE 1/16W
J 2
(3575 3150);
DISPLAY 0.510638 (3575 3150);
PAINT SKYBLUE (3575 3150);
DISPLAY INVISIBLE (3575 3150);
FORCEPROP 1 LAST PATH I163
J 0
(3550 3450);
DISPLAY 0.978723 (3550 3450);
PAINT WHITE (3550 3450);
DISPLAY INVISIBLE (3550 3450);
FORCEPROP 1 LAST TOLERANCE 1%
J 0
(3600 3200);
DISPLAY 0.510638 (3600 3200);
PAINT SKYBLUE (3600 3200);
DISPLAY INVISIBLE (3600 3200);
FORCEPROP 2 LAST CDS_LIB pure_quanta
J 0
(3600 3300);
DISPLAY INVISIBLE (3600 3300);
FORCEPROP 1 LAST LOCATION R335
J 0
(3375 3300);
DISPLAY 0.702128 (3375 3300);
PAINT YELLOW (3375 3300);
FORCEPROP 1 LASTPIN (3500 3300) $PN 1
J 0
(3512 3312);
DISPLAY 0.808511 (3512 3312);
PAINT WHITE (3512 3312);
FORCEPROP 1 LASTPIN (3700 3300) $PN 2
J 0
(3662 3312);
DISPLAY 0.808511 (3662 3312);
PAINT WHITE (3662 3312);
FORCEPROP 0 LAST $SEC 1
J 0
(3900 3350);
DISPLAY 0.680851 (3900 3350);
PAINT MONO (3900 3350);
DISPLAY INVISIBLE (3900 3350);
FORCEPROP 0 LAST CDS_SEC 1
J 0
(3900 3350);
DISPLAY 1.021277 (3900 3350);
DISPLAY INVISIBLE (3900 3350);
FORCEADD Q_RES..1
(3600 3450);
FORCEPROP 1 LAST MATERIAL CHIP
J 0
(3725 3450);
DISPLAY 0.510638 (3725 3450);
PAINT SKYBLUE (3725 3450);
FORCEPROP 1 LAST VALUE 120
J 2
(3925 3450);
DISPLAY 0.510638 (3925 3450);
PAINT SKYBLUE (3925 3450);
FORCEPROP 1 LAST PART_NUMBER CS11202FB02
J 0
(4250 3650);
DISPLAY 0.510638 (4250 3650);
PAINT WHITE (4250 3650);
DISPLAY INVISIBLE (4250 3650);
FORCEPROP 1 LAST PACK_TYPE 0402LF
J 0
(4300 3275);
DISPLAY 0.510638 (4300 3275);
PAINT SKYBLUE (4300 3275);
DISPLAY INVISIBLE (4300 3275);
FORCEPROP 1 LAST WATTAGE 1/16W
J 2
(3575 3300);
DISPLAY 0.510638 (3575 3300);
PAINT SKYBLUE (3575 3300);
DISPLAY INVISIBLE (3575 3300);
FORCEPROP 1 LAST PATH I164
J 0
(3550 3600);
DISPLAY 0.978723 (3550 3600);
PAINT WHITE (3550 3600);
DISPLAY INVISIBLE (3550 3600);
FORCEPROP 1 LAST TOLERANCE 1%
J 0
(3600 3350);
DISPLAY 0.510638 (3600 3350);
PAINT SKYBLUE (3600 3350);
DISPLAY INVISIBLE (3600 3350);
FORCEPROP 2 LAST CDS_LIB pure_quanta
J 0
(3600 3450);
DISPLAY INVISIBLE (3600 3450);
FORCEPROP 1 LAST LOCATION R334
J 0
(3375 3450);
DISPLAY 0.702128 (3375 3450);
PAINT YELLOW (3375 3450);
FORCEPROP 1 LASTPIN (3500 3450) $PN 1
J 0
(3512 3462);
DISPLAY 0.808511 (3512 3462);
PAINT WHITE (3512 3462);
FORCEPROP 1 LASTPIN (3700 3450) $PN 2
J 0
(3662 3462);
DISPLAY 0.808511 (3662 3462);
PAINT WHITE (3662 3462);
FORCEPROP 0 LAST $SEC 1
J 0
(3900 3500);
DISPLAY 0.680851 (3900 3500);
PAINT MONO (3900 3500);
DISPLAY INVISIBLE (3900 3500);
FORCEPROP 0 LAST CDS_SEC 1
J 0
(3900 3500);
DISPLAY 1.021277 (3900 3500);
DISPLAY INVISIBLE (3900 3500);
FORCEADD Q_RES..1
(4275 2700);
FORCEPROP 1 LAST PACK_TYPE 0402LF
J 0
(3975 2525);
DISPLAY 0.510638 (3975 2525);
PAINT SKYBLUE (3975 2525);
FORCEPROP 1 LAST TOLERANCE 1%
J 0
(4475 2525);
DISPLAY 0.510638 (4475 2525);
PAINT SKYBLUE (4475 2525);
FORCEPROP 1 LAST VALUE 120
J 2
(4625 2700);
DISPLAY 0.510638 (4625 2700);
PAINT SKYBLUE (4625 2700);
FORCEPROP 1 LAST WATTAGE 1/16W
J 2
(4425 2525);
DISPLAY 0.510638 (4425 2525);
PAINT SKYBLUE (4425 2525);
FORCEPROP 1 LAST PART_NUMBER CS11202FB02
J 0
(4050 2600);
DISPLAY 0.510638 (4050 2600);
PAINT WHITE (4050 2600);
FORCEPROP 1 LAST MATERIAL CHIP
J 0
(4400 2700);
DISPLAY 0.510638 (4400 2700);
PAINT SKYBLUE (4400 2700);
FORCEPROP 1 LAST PATH I165
J 0
(4225 2850);
DISPLAY 0.978723 (4225 2850);
PAINT WHITE (4225 2850);
DISPLAY INVISIBLE (4225 2850);
FORCEPROP 2 LAST CDS_LIB pure_quanta
J 0
(4275 2700);
DISPLAY INVISIBLE (4275 2700);
FORCEPROP 1 LAST LOCATION R364
J 0
(4025 2700);
DISPLAY 0.702128 (4025 2700);
PAINT YELLOW (4025 2700);
FORCEPROP 1 LASTPIN (4175 2700) $PN 1
J 0
(4187 2712);
DISPLAY 0.808511 (4187 2712);
PAINT WHITE (4187 2712);
FORCEPROP 1 LASTPIN (4375 2700) $PN 2
J 0
(4337 2712);
DISPLAY 0.808511 (4337 2712);
PAINT WHITE (4337 2712);
FORCEPROP 0 LAST $SEC 1
J 0
(4575 2750);
DISPLAY 0.680851 (4575 2750);
PAINT MONO (4575 2750);
DISPLAY INVISIBLE (4575 2750);
FORCEPROP 0 LAST CDS_SEC 1
J 0
(4575 2750);
DISPLAY 1.021277 (4575 2750);
DISPLAY INVISIBLE (4575 2750);
FORCEADD Q_RES..1
(4275 2850);
FORCEPROP 1 LAST VALUE 120
J 2
(4625 2850);
DISPLAY 0.510638 (4625 2850);
PAINT SKYBLUE (4625 2850);
FORCEPROP 1 LAST MATERIAL CHIP
J 0
(4400 2850);
DISPLAY 0.510638 (4400 2850);
PAINT SKYBLUE (4400 2850);
FORCEPROP 1 LAST PART_NUMBER CS11202FB02
J 0
(4950 2850);
DISPLAY 0.510638 (4950 2850);
PAINT WHITE (4950 2850);
DISPLAY INVISIBLE (4950 2850);
FORCEPROP 1 LAST PACK_TYPE 0402LF
J 0
(4525 2700);
DISPLAY 0.510638 (4525 2700);
PAINT SKYBLUE (4525 2700);
DISPLAY INVISIBLE (4525 2700);
FORCEPROP 1 LAST WATTAGE 1/16W
J 2
(4250 2700);
DISPLAY 0.510638 (4250 2700);
PAINT SKYBLUE (4250 2700);
DISPLAY INVISIBLE (4250 2700);
FORCEPROP 1 LAST PATH I166
J 0
(4225 3000);
DISPLAY 0.978723 (4225 3000);
PAINT WHITE (4225 3000);
DISPLAY INVISIBLE (4225 3000);
FORCEPROP 1 LAST TOLERANCE 1%
J 0
(4275 2750);
DISPLAY 0.510638 (4275 2750);
PAINT SKYBLUE (4275 2750);
DISPLAY INVISIBLE (4275 2750);
FORCEPROP 2 LAST CDS_LIB pure_quanta
J 0
(4275 2850);
DISPLAY INVISIBLE (4275 2850);
FORCEPROP 1 LAST LOCATION R363
J 0
(4025 2850);
DISPLAY 0.702128 (4025 2850);
PAINT YELLOW (4025 2850);
FORCEPROP 1 LASTPIN (4175 2850) $PN 1
J 0
(4187 2862);
DISPLAY 0.808511 (4187 2862);
PAINT WHITE (4187 2862);
FORCEPROP 1 LASTPIN (4375 2850) $PN 2
J 0
(4337 2862);
DISPLAY 0.808511 (4337 2862);
PAINT WHITE (4337 2862);
FORCEPROP 0 LAST $SEC 1
J 0
(4575 2900);
DISPLAY 0.680851 (4575 2900);
PAINT MONO (4575 2900);
DISPLAY INVISIBLE (4575 2900);
FORCEPROP 0 LAST CDS_SEC 1
J 0
(4575 2900);
DISPLAY 1.021277 (4575 2900);
DISPLAY INVISIBLE (4575 2900);
FORCEADD Q_RES..1
(4275 3150);
FORCEPROP 1 LAST VALUE 120
J 2
(4625 3150);
DISPLAY 0.510638 (4625 3150);
PAINT SKYBLUE (4625 3150);
FORCEPROP 1 LAST MATERIAL CHIP
J 0
(4400 3150);
DISPLAY 0.510638 (4400 3150);
PAINT SKYBLUE (4400 3150);
FORCEPROP 1 LAST PART_NUMBER CS11202FB02
J 0
(4750 3300);
DISPLAY 0.510638 (4750 3300);
PAINT WHITE (4750 3300);
DISPLAY INVISIBLE (4750 3300);
FORCEPROP 1 LAST PACK_TYPE 0402LF
J 0
(4525 3000);
DISPLAY 0.510638 (4525 3000);
PAINT SKYBLUE (4525 3000);
DISPLAY INVISIBLE (4525 3000);
FORCEPROP 1 LAST WATTAGE 1/16W
J 2
(4250 3000);
DISPLAY 0.510638 (4250 3000);
PAINT SKYBLUE (4250 3000);
DISPLAY INVISIBLE (4250 3000);
FORCEPROP 1 LAST PATH I167
J 0
(4225 3300);
DISPLAY 0.978723 (4225 3300);
PAINT WHITE (4225 3300);
DISPLAY INVISIBLE (4225 3300);
FORCEPROP 1 LAST TOLERANCE 1%
J 0
(4275 3050);
DISPLAY 0.510638 (4275 3050);
PAINT SKYBLUE (4275 3050);
DISPLAY INVISIBLE (4275 3050);
FORCEPROP 2 LAST CDS_LIB pure_quanta
J 0
(4275 3150);
DISPLAY INVISIBLE (4275 3150);
FORCEPROP 1 LAST LOCATION R361
J 0
(4050 3150);
DISPLAY 0.702128 (4050 3150);
PAINT YELLOW (4050 3150);
FORCEPROP 1 LASTPIN (4175 3150) $PN 1
J 0
(4187 3162);
DISPLAY 0.808511 (4187 3162);
PAINT WHITE (4187 3162);
FORCEPROP 1 LASTPIN (4375 3150) $PN 2
J 0
(4337 3162);
DISPLAY 0.808511 (4337 3162);
PAINT WHITE (4337 3162);
FORCEPROP 0 LAST $SEC 1
J 0
(4575 3200);
DISPLAY 0.680851 (4575 3200);
PAINT MONO (4575 3200);
DISPLAY INVISIBLE (4575 3200);
FORCEPROP 0 LAST CDS_SEC 1
J 0
(4575 3200);
DISPLAY 1.021277 (4575 3200);
DISPLAY INVISIBLE (4575 3200);
FORCEADD Q_RES..1
(4275 3000);
FORCEPROP 1 LAST MATERIAL CHIP
J 0
(4400 3000);
DISPLAY 0.510638 (4400 3000);
PAINT SKYBLUE (4400 3000);
FORCEPROP 1 LAST VALUE 120
J 2
(4625 3000);
DISPLAY 0.510638 (4625 3000);
PAINT SKYBLUE (4625 3000);
FORCEPROP 1 LAST PART_NUMBER CS11202FB02
J 0
(4950 3000);
DISPLAY 0.510638 (4950 3000);
PAINT WHITE (4950 3000);
DISPLAY INVISIBLE (4950 3000);
FORCEPROP 1 LAST PACK_TYPE 0402LF
J 0
(4525 2850);
DISPLAY 0.510638 (4525 2850);
PAINT SKYBLUE (4525 2850);
DISPLAY INVISIBLE (4525 2850);
FORCEPROP 1 LAST WATTAGE 1/16W
J 2
(4250 2850);
DISPLAY 0.510638 (4250 2850);
PAINT SKYBLUE (4250 2850);
DISPLAY INVISIBLE (4250 2850);
FORCEPROP 1 LAST PATH I168
J 0
(4225 3150);
DISPLAY 0.978723 (4225 3150);
PAINT WHITE (4225 3150);
DISPLAY INVISIBLE (4225 3150);
FORCEPROP 1 LAST TOLERANCE 1%
J 0
(4275 2900);
DISPLAY 0.510638 (4275 2900);
PAINT SKYBLUE (4275 2900);
DISPLAY INVISIBLE (4275 2900);
FORCEPROP 2 LAST CDS_LIB pure_quanta
J 0
(4275 3000);
DISPLAY INVISIBLE (4275 3000);
FORCEPROP 1 LAST LOCATION R362
J 0
(4025 3000);
DISPLAY 0.702128 (4025 3000);
PAINT YELLOW (4025 3000);
FORCEPROP 1 LASTPIN (4175 3000) $PN 1
J 0
(4187 3012);
DISPLAY 0.808511 (4187 3012);
PAINT WHITE (4187 3012);
FORCEPROP 1 LASTPIN (4375 3000) $PN 2
J 0
(4337 3012);
DISPLAY 0.808511 (4337 3012);
PAINT WHITE (4337 3012);
FORCEPROP 0 LAST $SEC 1
J 0
(4575 3050);
DISPLAY 0.680851 (4575 3050);
PAINT MONO (4575 3050);
DISPLAY INVISIBLE (4575 3050);
FORCEPROP 0 LAST CDS_SEC 1
J 0
(4575 3050);
DISPLAY 1.021277 (4575 3050);
DISPLAY INVISIBLE (4575 3050);
FORCEADD Q_RES..1
(4275 3300);
FORCEPROP 1 LAST MATERIAL CHIP
J 0
(4400 3300);
DISPLAY 0.510638 (4400 3300);
PAINT SKYBLUE (4400 3300);
FORCEPROP 1 LAST VALUE 120
J 2
(4625 3300);
DISPLAY 0.510638 (4625 3300);
PAINT SKYBLUE (4625 3300);
FORCEPROP 1 LAST PART_NUMBER CS11202FB02
J 0
(4850 3475);
DISPLAY 0.510638 (4850 3475);
PAINT WHITE (4850 3475);
DISPLAY INVISIBLE (4850 3475);
FORCEPROP 1 LAST PACK_TYPE 0402LF
J 0
(4525 3150);
DISPLAY 0.510638 (4525 3150);
PAINT SKYBLUE (4525 3150);
DISPLAY INVISIBLE (4525 3150);
FORCEPROP 1 LAST WATTAGE 1/16W
J 2
(4250 3150);
DISPLAY 0.510638 (4250 3150);
PAINT SKYBLUE (4250 3150);
DISPLAY INVISIBLE (4250 3150);
FORCEPROP 1 LAST PATH I169
J 0
(4225 3450);
DISPLAY 0.978723 (4225 3450);
PAINT WHITE (4225 3450);
DISPLAY INVISIBLE (4225 3450);
FORCEPROP 1 LAST TOLERANCE 1%
J 0
(4275 3200);
DISPLAY 0.510638 (4275 3200);
PAINT SKYBLUE (4275 3200);
DISPLAY INVISIBLE (4275 3200);
FORCEPROP 2 LAST CDS_LIB pure_quanta
J 0
(4275 3300);
DISPLAY INVISIBLE (4275 3300);
FORCEPROP 1 LAST LOCATION R360
J 0
(4050 3300);
DISPLAY 0.702128 (4050 3300);
PAINT YELLOW (4050 3300);
FORCEPROP 1 LASTPIN (4175 3300) $PN 1
J 0
(4187 3312);
DISPLAY 0.808511 (4187 3312);
PAINT WHITE (4187 3312);
FORCEPROP 1 LASTPIN (4375 3300) $PN 2
J 0
(4337 3312);
DISPLAY 0.808511 (4337 3312);
PAINT WHITE (4337 3312);
FORCEPROP 0 LAST $SEC 1
J 0
(4575 3350);
DISPLAY 0.680851 (4575 3350);
PAINT MONO (4575 3350);
DISPLAY INVISIBLE (4575 3350);
FORCEPROP 0 LAST CDS_SEC 1
J 0
(4575 3350);
DISPLAY 1.021277 (4575 3350);
DISPLAY INVISIBLE (4575 3350);
FORCEADD Q_RES..1
(-2350 -450);
FORCEPROP 1 LAST VALUE 0
J 2
(-2150 -450);
DISPLAY 0.510638 (-2150 -450);
PAINT SKYBLUE (-2150 -450);
FORCEPROP 1 LAST TOLERANCE 5%
J 0
(-2125 -375);
DISPLAY 0.510638 (-2125 -375);
PAINT SKYBLUE (-2125 -375);
FORCEPROP 1 LAST MATERIAL CHIP
J 0
(-2425 -375);
DISPLAY 0.510638 (-2425 -375);
PAINT SKYBLUE (-2425 -375);
FORCEPROP 1 LAST PACK_TYPE 0402LF
J 0
(-2625 -375);
DISPLAY 0.510638 (-2625 -375);
PAINT SKYBLUE (-2625 -375);
FORCEPROP 1 LAST WATTAGE 1/16W
J 2
(-2175 -375);
DISPLAY 0.510638 (-2175 -375);
PAINT SKYBLUE (-2175 -375);
FORCEPROP 1 LAST PART_NUMBER CS00002JB13
J 0
(-2625 -300);
DISPLAY 0.510638 (-2625 -300);
PAINT WHITE (-2625 -300);
FORCEPROP 1 LAST PATH I17
J 0
(-2400 -300);
DISPLAY 0.978723 (-2400 -300);
PAINT WHITE (-2400 -300);
DISPLAY INVISIBLE (-2400 -300);
FORCEPROP 2 LAST SEC_TYPE 0402LF
J 0
(-2400 -250);
DISPLAY 0.680851 (-2400 -250);
DISPLAY INVISIBLE (-2400 -250);
FORCEPROP 2 LAST CDS_LIB pure_quanta
J 0
(-2350 -450);
DISPLAY INVISIBLE (-2350 -450);
FORCEPROP 1 LAST LOCATION R3
J 0
(-2575 -450);
DISPLAY 0.702128 (-2575 -450);
PAINT YELLOW (-2575 -450);
FORCEPROP 1 LASTPIN (-2450 -450) $PN 1
J 0
(-2438 -438);
DISPLAY 0.808511 (-2438 -438);
PAINT WHITE (-2438 -438);
FORCEPROP 1 LASTPIN (-2250 -450) $PN 2
J 0
(-2288 -438);
DISPLAY 0.808511 (-2288 -438);
PAINT WHITE (-2288 -438);
FORCEPROP 2 LAST SEC 1
J 0
(-2400 -250);
DISPLAY 0.680851 (-2400 -250);
PAINT MONO (-2400 -250);
DISPLAY INVISIBLE (-2400 -250);
FORCEADD Q_RES..1
(4275 3450);
FORCEPROP 1 LAST MATERIAL CHIP
J 0
(4400 3450);
DISPLAY 0.510638 (4400 3450);
PAINT SKYBLUE (4400 3450);
FORCEPROP 1 LAST VALUE 120
J 2
(4625 3450);
DISPLAY 0.510638 (4625 3450);
PAINT SKYBLUE (4625 3450);
FORCEPROP 1 LAST PART_NUMBER CS11202FB02
J 0
(4950 3525);
DISPLAY 0.510638 (4950 3525);
PAINT WHITE (4950 3525);
DISPLAY INVISIBLE (4950 3525);
FORCEPROP 1 LAST PACK_TYPE 0402LF
J 0
(5025 3275);
DISPLAY 0.510638 (5025 3275);
PAINT SKYBLUE (5025 3275);
DISPLAY INVISIBLE (5025 3275);
FORCEPROP 1 LAST WATTAGE 1/16W
J 2
(4250 3300);
DISPLAY 0.510638 (4250 3300);
PAINT SKYBLUE (4250 3300);
DISPLAY INVISIBLE (4250 3300);
FORCEPROP 1 LAST PATH I170
J 0
(4225 3600);
DISPLAY 0.978723 (4225 3600);
PAINT WHITE (4225 3600);
DISPLAY INVISIBLE (4225 3600);
FORCEPROP 1 LAST TOLERANCE 1%
J 0
(4275 3350);
DISPLAY 0.510638 (4275 3350);
PAINT SKYBLUE (4275 3350);
DISPLAY INVISIBLE (4275 3350);
FORCEPROP 2 LAST CDS_LIB pure_quanta
J 0
(4275 3450);
DISPLAY INVISIBLE (4275 3450);
FORCEPROP 1 LAST LOCATION R359
J 0
(4050 3450);
DISPLAY 0.702128 (4050 3450);
PAINT YELLOW (4050 3450);
FORCEPROP 1 LASTPIN (4175 3450) $PN 1
J 0
(4190 3460);
DISPLAY 0.808511 (4190 3460);
PAINT WHITE (4190 3460);
FORCEPROP 1 LASTPIN (4375 3450) $PN 2
J 0
(4337 3462);
DISPLAY 0.808511 (4337 3462);
PAINT WHITE (4337 3462);
FORCEPROP 0 LAST $SEC 1
J 0
(4575 3500);
DISPLAY 0.680851 (4575 3500);
PAINT MONO (4575 3500);
DISPLAY INVISIBLE (4575 3500);
FORCEPROP 0 LAST CDS_SEC 1
J 0
(4575 3500);
DISPLAY 1.021277 (4575 3500);
DISPLAY INVISIBLE (4575 3500);
FORCEADD Q_RES..1
(3600 3750);
FORCEPROP 1 LAST MATERIAL CHIP
J 0
(3725 3750);
DISPLAY 0.510638 (3725 3750);
PAINT SKYBLUE (3725 3750);
FORCEPROP 1 LAST VALUE 120
J 2
(3925 3750);
DISPLAY 0.510638 (3925 3750);
PAINT SKYBLUE (3925 3750);
FORCEPROP 1 LAST PART_NUMBER CS11202FB02
J 0
(3550 3850);
DISPLAY 0.510638 (3550 3850);
PAINT WHITE (3550 3850);
DISPLAY INVISIBLE (3550 3850);
FORCEPROP 1 LAST PACK_TYPE 0402LF
J 0
(3850 3600);
DISPLAY 0.510638 (3850 3600);
PAINT SKYBLUE (3850 3600);
DISPLAY INVISIBLE (3850 3600);
FORCEPROP 1 LAST WATTAGE 1/16W
J 2
(3575 3600);
DISPLAY 0.510638 (3575 3600);
PAINT SKYBLUE (3575 3600);
DISPLAY INVISIBLE (3575 3600);
FORCEPROP 1 LAST PATH I171
J 0
(3550 3900);
DISPLAY 0.978723 (3550 3900);
PAINT WHITE (3550 3900);
DISPLAY INVISIBLE (3550 3900);
FORCEPROP 1 LAST TOLERANCE 1%
J 0
(3600 3650);
DISPLAY 0.510638 (3600 3650);
PAINT SKYBLUE (3600 3650);
DISPLAY INVISIBLE (3600 3650);
FORCEPROP 2 LAST CDS_LIB pure_quanta
J 0
(3600 3750);
DISPLAY INVISIBLE (3600 3750);
FORCEPROP 1 LAST LOCATION R332
J 2
(3475 3750);
DISPLAY 0.702128 (3475 3750);
PAINT YELLOW (3475 3750);
FORCEPROP 1 LASTPIN (3500 3750) $PN 1
J 0
(3512 3762);
DISPLAY 0.808511 (3512 3762);
PAINT WHITE (3512 3762);
FORCEPROP 1 LASTPIN (3700 3750) $PN 2
J 0
(3662 3762);
DISPLAY 0.808511 (3662 3762);
PAINT WHITE (3662 3762);
FORCEPROP 0 LAST $SEC 1
J 0
(3900 3800);
DISPLAY 0.680851 (3900 3800);
PAINT MONO (3900 3800);
DISPLAY INVISIBLE (3900 3800);
FORCEPROP 0 LAST CDS_SEC 1
J 0
(3900 3800);
DISPLAY 1.021277 (3900 3800);
DISPLAY INVISIBLE (3900 3800);
FORCEADD Q_RES..1
(3600 3600);
FORCEPROP 1 LAST MATERIAL CHIP
J 0
(3725 3600);
DISPLAY 0.510638 (3725 3600);
PAINT SKYBLUE (3725 3600);
FORCEPROP 1 LAST VALUE 120
J 2
(3925 3600);
DISPLAY 0.510638 (3925 3600);
PAINT SKYBLUE (3925 3600);
FORCEPROP 1 LAST PART_NUMBER CS11202FB02
J 0
(4425 3675);
DISPLAY 0.510638 (4425 3675);
PAINT WHITE (4425 3675);
DISPLAY INVISIBLE (4425 3675);
FORCEPROP 1 LAST PACK_TYPE 0402LF
J 0
(4650 3375);
DISPLAY 0.510638 (4650 3375);
PAINT SKYBLUE (4650 3375);
DISPLAY INVISIBLE (4650 3375);
FORCEPROP 1 LAST WATTAGE 1/16W
J 2
(3575 3450);
DISPLAY 0.510638 (3575 3450);
PAINT SKYBLUE (3575 3450);
DISPLAY INVISIBLE (3575 3450);
FORCEPROP 1 LAST PATH I172
J 0
(3550 3750);
DISPLAY 0.978723 (3550 3750);
PAINT WHITE (3550 3750);
DISPLAY INVISIBLE (3550 3750);
FORCEPROP 1 LAST TOLERANCE 1%
J 0
(3600 3500);
DISPLAY 0.510638 (3600 3500);
PAINT SKYBLUE (3600 3500);
DISPLAY INVISIBLE (3600 3500);
FORCEPROP 2 LAST CDS_LIB pure_quanta
J 0
(3600 3600);
DISPLAY INVISIBLE (3600 3600);
FORCEPROP 1 LAST LOCATION R333
J 0
(3375 3600);
DISPLAY 0.702128 (3375 3600);
PAINT YELLOW (3375 3600);
FORCEPROP 1 LASTPIN (3500 3600) $PN 1
J 0
(3512 3612);
DISPLAY 0.808511 (3512 3612);
PAINT WHITE (3512 3612);
FORCEPROP 1 LASTPIN (3700 3600) $PN 2
J 0
(3662 3612);
DISPLAY 0.808511 (3662 3612);
PAINT WHITE (3662 3612);
FORCEPROP 0 LAST $SEC 1
J 0
(3900 3650);
DISPLAY 0.680851 (3900 3650);
PAINT MONO (3900 3650);
DISPLAY INVISIBLE (3900 3650);
FORCEPROP 0 LAST CDS_SEC 1
J 0
(3900 3650);
DISPLAY 1.021277 (3900 3650);
DISPLAY INVISIBLE (3900 3650);
FORCEADD Q_RES..1
(3600 3900);
FORCEPROP 1 LAST MATERIAL CHIP
J 0
(3725 3900);
DISPLAY 0.510638 (3725 3900);
PAINT SKYBLUE (3725 3900);
FORCEPROP 1 LAST VALUE 120
J 2
(3925 3900);
DISPLAY 0.510638 (3925 3900);
PAINT SKYBLUE (3925 3900);
FORCEPROP 1 LAST PART_NUMBER CS11202FB02
J 0
(3550 4000);
DISPLAY 0.510638 (3550 4000);
PAINT WHITE (3550 4000);
DISPLAY INVISIBLE (3550 4000);
FORCEPROP 1 LAST PACK_TYPE 0402LF
J 0
(3850 3750);
DISPLAY 0.510638 (3850 3750);
PAINT SKYBLUE (3850 3750);
DISPLAY INVISIBLE (3850 3750);
FORCEPROP 1 LAST WATTAGE 1/16W
J 2
(3575 3750);
DISPLAY 0.510638 (3575 3750);
PAINT SKYBLUE (3575 3750);
DISPLAY INVISIBLE (3575 3750);
FORCEPROP 1 LAST PATH I173
J 0
(3550 4050);
DISPLAY 0.978723 (3550 4050);
PAINT WHITE (3550 4050);
DISPLAY INVISIBLE (3550 4050);
FORCEPROP 1 LAST TOLERANCE 1%
J 0
(3600 3800);
DISPLAY 0.510638 (3600 3800);
PAINT SKYBLUE (3600 3800);
DISPLAY INVISIBLE (3600 3800);
FORCEPROP 2 LAST CDS_LIB pure_quanta
J 0
(3600 3900);
DISPLAY INVISIBLE (3600 3900);
FORCEPROP 1 LAST LOCATION R331
J 2
(3475 3900);
DISPLAY 0.702128 (3475 3900);
PAINT YELLOW (3475 3900);
FORCEPROP 1 LASTPIN (3500 3900) $PN 1
J 0
(3512 3912);
DISPLAY 0.808511 (3512 3912);
PAINT WHITE (3512 3912);
FORCEPROP 1 LASTPIN (3700 3900) $PN 2
J 0
(3662 3912);
DISPLAY 0.808511 (3662 3912);
PAINT WHITE (3662 3912);
FORCEPROP 0 LAST $SEC 1
J 0
(3900 3950);
DISPLAY 0.680851 (3900 3950);
PAINT MONO (3900 3950);
DISPLAY INVISIBLE (3900 3950);
FORCEPROP 0 LAST CDS_SEC 1
J 0
(3900 3950);
DISPLAY 1.021277 (3900 3950);
DISPLAY INVISIBLE (3900 3950);
FORCEADD Q_RES..1
(3600 4050);
FORCEPROP 1 LAST VALUE 120
J 2
(3925 4050);
DISPLAY 0.510638 (3925 4050);
PAINT SKYBLUE (3925 4050);
FORCEPROP 1 LAST MATERIAL CHIP
J 0
(3725 4050);
DISPLAY 0.510638 (3725 4050);
PAINT SKYBLUE (3725 4050);
FORCEPROP 1 LAST PART_NUMBER CS11202FB02
J 0
(3550 4150);
DISPLAY 0.510638 (3550 4150);
PAINT WHITE (3550 4150);
DISPLAY INVISIBLE (3550 4150);
FORCEPROP 1 LAST PACK_TYPE 0402LF
J 0
(3850 3900);
DISPLAY 0.510638 (3850 3900);
PAINT SKYBLUE (3850 3900);
DISPLAY INVISIBLE (3850 3900);
FORCEPROP 1 LAST WATTAGE 1/16W
J 2
(3575 3900);
DISPLAY 0.510638 (3575 3900);
PAINT SKYBLUE (3575 3900);
DISPLAY INVISIBLE (3575 3900);
FORCEPROP 1 LAST PATH I174
J 0
(3550 4200);
DISPLAY 0.978723 (3550 4200);
PAINT WHITE (3550 4200);
DISPLAY INVISIBLE (3550 4200);
FORCEPROP 1 LAST TOLERANCE 1%
J 0
(3600 3950);
DISPLAY 0.510638 (3600 3950);
PAINT SKYBLUE (3600 3950);
DISPLAY INVISIBLE (3600 3950);
FORCEPROP 2 LAST CDS_LIB pure_quanta
J 0
(3600 4050);
DISPLAY INVISIBLE (3600 4050);
FORCEPROP 1 LAST LOCATION R330
J 2
(3475 4050);
DISPLAY 0.702128 (3475 4050);
PAINT YELLOW (3475 4050);
FORCEPROP 1 LASTPIN (3500 4050) $PN 1
J 0
(3512 4062);
DISPLAY 0.808511 (3512 4062);
PAINT WHITE (3512 4062);
FORCEPROP 1 LASTPIN (3700 4050) $PN 2
J 0
(3662 4062);
DISPLAY 0.808511 (3662 4062);
PAINT WHITE (3662 4062);
FORCEPROP 0 LAST $SEC 1
J 0
(3900 4100);
DISPLAY 0.680851 (3900 4100);
PAINT MONO (3900 4100);
DISPLAY INVISIBLE (3900 4100);
FORCEPROP 0 LAST CDS_SEC 1
J 0
(3900 4100);
DISPLAY 1.021277 (3900 4100);
DISPLAY INVISIBLE (3900 4100);
FORCEADD Q_RES..1
(3600 4200);
FORCEPROP 1 LAST MATERIAL CHIP
J 0
(3725 4200);
DISPLAY 0.510638 (3725 4200);
PAINT SKYBLUE (3725 4200);
FORCEPROP 1 LAST VALUE 120
J 2
(3925 4200);
DISPLAY 0.510638 (3925 4200);
PAINT SKYBLUE (3925 4200);
FORCEPROP 1 LAST PART_NUMBER CS11202FB02
J 0
(3550 4300);
DISPLAY 0.510638 (3550 4300);
PAINT WHITE (3550 4300);
DISPLAY INVISIBLE (3550 4300);
FORCEPROP 1 LAST PACK_TYPE 0402LF
J 0
(3850 4050);
DISPLAY 0.510638 (3850 4050);
PAINT SKYBLUE (3850 4050);
DISPLAY INVISIBLE (3850 4050);
FORCEPROP 1 LAST WATTAGE 1/16W
J 2
(3575 4050);
DISPLAY 0.510638 (3575 4050);
PAINT SKYBLUE (3575 4050);
DISPLAY INVISIBLE (3575 4050);
FORCEPROP 1 LAST PATH I175
J 0
(3550 4350);
DISPLAY 0.978723 (3550 4350);
PAINT WHITE (3550 4350);
DISPLAY INVISIBLE (3550 4350);
FORCEPROP 1 LAST TOLERANCE 1%
J 0
(3600 4100);
DISPLAY 0.510638 (3600 4100);
PAINT SKYBLUE (3600 4100);
DISPLAY INVISIBLE (3600 4100);
FORCEPROP 2 LAST CDS_LIB pure_quanta
J 0
(3600 4200);
DISPLAY INVISIBLE (3600 4200);
FORCEPROP 1 LAST LOCATION R329
J 2
(3475 4200);
DISPLAY 0.702128 (3475 4200);
PAINT YELLOW (3475 4200);
FORCEPROP 1 LASTPIN (3500 4200) $PN 1
J 0
(3512 4212);
DISPLAY 0.808511 (3512 4212);
PAINT WHITE (3512 4212);
FORCEPROP 1 LASTPIN (3700 4200) $PN 2
J 0
(3662 4212);
DISPLAY 0.808511 (3662 4212);
PAINT WHITE (3662 4212);
FORCEPROP 0 LAST $SEC 1
J 0
(3900 4250);
DISPLAY 0.680851 (3900 4250);
PAINT MONO (3900 4250);
DISPLAY INVISIBLE (3900 4250);
FORCEPROP 0 LAST CDS_SEC 1
J 0
(3900 4250);
DISPLAY 1.021277 (3900 4250);
DISPLAY INVISIBLE (3900 4250);
FORCEADD Q_RES..1
(3600 4350);
FORCEPROP 1 LAST MATERIAL CHIP
J 0
(3725 4350);
DISPLAY 0.510638 (3725 4350);
PAINT SKYBLUE (3725 4350);
FORCEPROP 1 LAST VALUE 120
J 2
(3925 4350);
DISPLAY 0.510638 (3925 4350);
PAINT SKYBLUE (3925 4350);
FORCEPROP 1 LAST PART_NUMBER CS11202FB02
J 0
(3550 4450);
DISPLAY 0.510638 (3550 4450);
PAINT WHITE (3550 4450);
DISPLAY INVISIBLE (3550 4450);
FORCEPROP 1 LAST PACK_TYPE 0402LF
J 0
(3850 4200);
DISPLAY 0.510638 (3850 4200);
PAINT SKYBLUE (3850 4200);
DISPLAY INVISIBLE (3850 4200);
FORCEPROP 1 LAST WATTAGE 1/16W
J 2
(3575 4200);
DISPLAY 0.510638 (3575 4200);
PAINT SKYBLUE (3575 4200);
DISPLAY INVISIBLE (3575 4200);
FORCEPROP 1 LAST PATH I176
J 0
(3550 4500);
DISPLAY 0.978723 (3550 4500);
PAINT WHITE (3550 4500);
DISPLAY INVISIBLE (3550 4500);
FORCEPROP 1 LAST TOLERANCE 1%
J 0
(3600 4250);
DISPLAY 0.510638 (3600 4250);
PAINT SKYBLUE (3600 4250);
DISPLAY INVISIBLE (3600 4250);
FORCEPROP 2 LAST CDS_LIB pure_quanta
J 0
(3600 4350);
DISPLAY INVISIBLE (3600 4350);
FORCEPROP 1 LAST LOCATION R328
J 2
(3475 4350);
DISPLAY 0.702128 (3475 4350);
PAINT YELLOW (3475 4350);
FORCEPROP 1 LASTPIN (3500 4350) $PN 1
J 0
(3512 4362);
DISPLAY 0.808511 (3512 4362);
PAINT WHITE (3512 4362);
FORCEPROP 1 LASTPIN (3700 4350) $PN 2
J 0
(3662 4362);
DISPLAY 0.808511 (3662 4362);
PAINT WHITE (3662 4362);
FORCEPROP 0 LAST $SEC 1
J 0
(3900 4400);
DISPLAY 0.680851 (3900 4400);
PAINT MONO (3900 4400);
DISPLAY INVISIBLE (3900 4400);
FORCEPROP 0 LAST CDS_SEC 1
J 0
(3900 4400);
DISPLAY 1.021277 (3900 4400);
DISPLAY INVISIBLE (3900 4400);
FORCEADD Q_RES..1
(3600 4500);
FORCEPROP 1 LAST MATERIAL CHIP
J 0
(3725 4500);
DISPLAY 0.510638 (3725 4500);
PAINT SKYBLUE (3725 4500);
FORCEPROP 1 LAST VALUE 120
J 2
(3925 4500);
DISPLAY 0.510638 (3925 4500);
PAINT SKYBLUE (3925 4500);
FORCEPROP 1 LAST PART_NUMBER CS11202FB02
J 0
(3550 4600);
DISPLAY 0.510638 (3550 4600);
PAINT WHITE (3550 4600);
DISPLAY INVISIBLE (3550 4600);
FORCEPROP 1 LAST PACK_TYPE 0402LF
J 0
(3850 4350);
DISPLAY 0.510638 (3850 4350);
PAINT SKYBLUE (3850 4350);
DISPLAY INVISIBLE (3850 4350);
FORCEPROP 1 LAST WATTAGE 1/16W
J 2
(3575 4350);
DISPLAY 0.510638 (3575 4350);
PAINT SKYBLUE (3575 4350);
DISPLAY INVISIBLE (3575 4350);
FORCEPROP 1 LAST PATH I177
J 0
(3550 4650);
DISPLAY 0.978723 (3550 4650);
PAINT WHITE (3550 4650);
DISPLAY INVISIBLE (3550 4650);
FORCEPROP 1 LAST TOLERANCE 1%
J 0
(3600 4400);
DISPLAY 0.510638 (3600 4400);
PAINT SKYBLUE (3600 4400);
DISPLAY INVISIBLE (3600 4400);
FORCEPROP 2 LAST CDS_LIB pure_quanta
J 0
(3600 4500);
DISPLAY INVISIBLE (3600 4500);
FORCEPROP 1 LAST LOCATION R327
J 2
(3475 4500);
DISPLAY 0.702128 (3475 4500);
PAINT YELLOW (3475 4500);
FORCEPROP 1 LASTPIN (3500 4500) $PN 1
J 0
(3512 4512);
DISPLAY 0.808511 (3512 4512);
PAINT WHITE (3512 4512);
FORCEPROP 1 LASTPIN (3700 4500) $PN 2
J 0
(3662 4512);
DISPLAY 0.808511 (3662 4512);
PAINT WHITE (3662 4512);
FORCEPROP 0 LAST $SEC 1
J 0
(3900 4550);
DISPLAY 0.680851 (3900 4550);
PAINT MONO (3900 4550);
DISPLAY INVISIBLE (3900 4550);
FORCEPROP 0 LAST CDS_SEC 1
J 0
(3900 4550);
DISPLAY 1.021277 (3900 4550);
DISPLAY INVISIBLE (3900 4550);
FORCEADD Q_RES..1
(4275 3600);
FORCEPROP 1 LAST MATERIAL CHIP
J 0
(4400 3600);
DISPLAY 0.510638 (4400 3600);
PAINT SKYBLUE (4400 3600);
FORCEPROP 1 LAST VALUE 120
J 2
(4625 3600);
DISPLAY 0.510638 (4625 3600);
PAINT SKYBLUE (4625 3600);
FORCEPROP 1 LAST PART_NUMBER CS11202FB02
J 0
(5025 3625);
DISPLAY 0.510638 (5025 3625);
PAINT WHITE (5025 3625);
DISPLAY INVISIBLE (5025 3625);
FORCEPROP 1 LAST PACK_TYPE 0402LF
J 0
(5125 3500);
DISPLAY 0.510638 (5125 3500);
PAINT SKYBLUE (5125 3500);
DISPLAY INVISIBLE (5125 3500);
FORCEPROP 1 LAST WATTAGE 1/16W
J 2
(4250 3450);
DISPLAY 0.510638 (4250 3450);
PAINT SKYBLUE (4250 3450);
DISPLAY INVISIBLE (4250 3450);
FORCEPROP 1 LAST PATH I178
J 0
(4225 3750);
DISPLAY 0.978723 (4225 3750);
PAINT WHITE (4225 3750);
DISPLAY INVISIBLE (4225 3750);
FORCEPROP 1 LAST TOLERANCE 1%
J 0
(4275 3500);
DISPLAY 0.510638 (4275 3500);
PAINT SKYBLUE (4275 3500);
DISPLAY INVISIBLE (4275 3500);
FORCEPROP 2 LAST CDS_LIB pure_quanta
J 0
(4275 3600);
DISPLAY INVISIBLE (4275 3600);
FORCEPROP 1 LAST LOCATION R358
J 0
(4050 3600);
DISPLAY 0.702128 (4050 3600);
PAINT YELLOW (4050 3600);
FORCEPROP 1 LASTPIN (4175 3600) $PN 1
J 0
(4187 3612);
DISPLAY 0.808511 (4187 3612);
PAINT WHITE (4187 3612);
FORCEPROP 1 LASTPIN (4375 3600) $PN 2
J 0
(4337 3612);
DISPLAY 0.808511 (4337 3612);
PAINT WHITE (4337 3612);
FORCEPROP 0 LAST $SEC 1
J 0
(4575 3650);
DISPLAY 0.680851 (4575 3650);
PAINT MONO (4575 3650);
DISPLAY INVISIBLE (4575 3650);
FORCEPROP 0 LAST CDS_SEC 1
J 0
(4575 3650);
DISPLAY 1.021277 (4575 3650);
DISPLAY INVISIBLE (4575 3650);
FORCEADD Q_RES..1
(4275 3750);
FORCEPROP 1 LAST MATERIAL CHIP
J 0
(4400 3750);
DISPLAY 0.510638 (4400 3750);
PAINT SKYBLUE (4400 3750);
FORCEPROP 1 LAST VALUE 120
J 2
(4625 3750);
DISPLAY 0.510638 (4625 3750);
PAINT SKYBLUE (4625 3750);
FORCEPROP 1 LAST PART_NUMBER CS11202FB02
J 0
(4225 3850);
DISPLAY 0.510638 (4225 3850);
PAINT WHITE (4225 3850);
DISPLAY INVISIBLE (4225 3850);
FORCEPROP 1 LAST PACK_TYPE 0402LF
J 0
(4525 3600);
DISPLAY 0.510638 (4525 3600);
PAINT SKYBLUE (4525 3600);
DISPLAY INVISIBLE (4525 3600);
FORCEPROP 1 LAST WATTAGE 1/16W
J 2
(4250 3600);
DISPLAY 0.510638 (4250 3600);
PAINT SKYBLUE (4250 3600);
DISPLAY INVISIBLE (4250 3600);
FORCEPROP 1 LAST PATH I179
J 0
(4225 3900);
DISPLAY 0.978723 (4225 3900);
PAINT WHITE (4225 3900);
DISPLAY INVISIBLE (4225 3900);
FORCEPROP 1 LAST TOLERANCE 1%
J 0
(4275 3650);
DISPLAY 0.510638 (4275 3650);
PAINT SKYBLUE (4275 3650);
DISPLAY INVISIBLE (4275 3650);
FORCEPROP 2 LAST CDS_LIB pure_quanta
J 0
(4275 3750);
DISPLAY INVISIBLE (4275 3750);
FORCEPROP 1 LAST LOCATION R357
J 2
(4150 3750);
DISPLAY 0.702128 (4150 3750);
PAINT YELLOW (4150 3750);
FORCEPROP 1 LASTPIN (4175 3750) $PN 1
J 0
(4187 3762);
DISPLAY 0.808511 (4187 3762);
PAINT WHITE (4187 3762);
FORCEPROP 1 LASTPIN (4375 3750) $PN 2
J 0
(4337 3762);
DISPLAY 0.808511 (4337 3762);
PAINT WHITE (4337 3762);
FORCEPROP 0 LAST $SEC 1
J 0
(4575 3800);
DISPLAY 0.680851 (4575 3800);
PAINT MONO (4575 3800);
DISPLAY INVISIBLE (4575 3800);
FORCEPROP 0 LAST CDS_SEC 1
J 0
(4575 3800);
DISPLAY 1.021277 (4575 3800);
DISPLAY INVISIBLE (4575 3800);
FORCEADD OFFPAGE..4
(-1250 -850);
FORCEPROP 2 LAST $XR1 20 
J 0
(-974 -850);
DISPLAY 0.638298 (-974 -850);
PAINT MONO (-974 -850);
FORCEPROP 2 LAST $XR0 12 
J 0
(-1064 -850);
DISPLAY 0.638298 (-1064 -850);
PAINT MONO (-1064 -850);
FORCEPROP 2 LAST PATH I18
J 0
(-1000 -800);
DISPLAY 1.021277 (-1000 -800);
DISPLAY INVISIBLE (-1000 -800);
FORCEPROP 1 LAST COMMENT_BODY TRUE
J 0
(-1275 -950);
DISPLAY 1.574468 (-1275 -950);
PAINT PEACH (-1275 -950);
DISPLAY INVISIBLE (-1275 -950);
FORCEPROP 1 LAST OFFPAGE TRUE
J 0
(-925 -975);
DISPLAY 1.574468 (-925 -975);
PAINT GREEN (-925 -975);
DISPLAY INVISIBLE (-925 -975);
FORCEPROP 2 LAST CDS_LIB standard
J 0
(-1250 -850);
DISPLAY INVISIBLE (-1250 -850);
FORCEADD Q_RES..1
(4275 3900);
FORCEPROP 1 LAST MATERIAL CHIP
J 0
(4400 3900);
DISPLAY 0.510638 (4400 3900);
PAINT SKYBLUE (4400 3900);
FORCEPROP 1 LAST VALUE 120
J 2
(4625 3900);
DISPLAY 0.510638 (4625 3900);
PAINT SKYBLUE (4625 3900);
FORCEPROP 1 LAST PART_NUMBER CS11202FB02
J 0
(4225 4000);
DISPLAY 0.510638 (4225 4000);
PAINT WHITE (4225 4000);
DISPLAY INVISIBLE (4225 4000);
FORCEPROP 1 LAST PACK_TYPE 0402LF
J 0
(4525 3750);
DISPLAY 0.510638 (4525 3750);
PAINT SKYBLUE (4525 3750);
DISPLAY INVISIBLE (4525 3750);
FORCEPROP 1 LAST WATTAGE 1/16W
J 2
(4250 3750);
DISPLAY 0.510638 (4250 3750);
PAINT SKYBLUE (4250 3750);
DISPLAY INVISIBLE (4250 3750);
FORCEPROP 1 LAST PATH I180
J 0
(4225 4050);
DISPLAY 0.978723 (4225 4050);
PAINT WHITE (4225 4050);
DISPLAY INVISIBLE (4225 4050);
FORCEPROP 1 LAST TOLERANCE 1%
J 0
(4275 3800);
DISPLAY 0.510638 (4275 3800);
PAINT SKYBLUE (4275 3800);
DISPLAY INVISIBLE (4275 3800);
FORCEPROP 2 LAST CDS_LIB pure_quanta
J 0
(4275 3900);
DISPLAY INVISIBLE (4275 3900);
FORCEPROP 1 LAST LOCATION R356
J 2
(4150 3900);
DISPLAY 0.702128 (4150 3900);
PAINT YELLOW (4150 3900);
FORCEPROP 1 LASTPIN (4175 3900) $PN 1
J 0
(4187 3912);
DISPLAY 0.808511 (4187 3912);
PAINT WHITE (4187 3912);
FORCEPROP 1 LASTPIN (4375 3900) $PN 2
J 0
(4337 3912);
DISPLAY 0.808511 (4337 3912);
PAINT WHITE (4337 3912);
FORCEPROP 0 LAST $SEC 1
J 0
(4575 3950);
DISPLAY 0.680851 (4575 3950);
PAINT MONO (4575 3950);
DISPLAY INVISIBLE (4575 3950);
FORCEPROP 0 LAST CDS_SEC 1
J 0
(4575 3950);
DISPLAY 1.021277 (4575 3950);
DISPLAY INVISIBLE (4575 3950);
FORCEADD Q_RES..1
(4275 4200);
FORCEPROP 1 LAST MATERIAL CHIP
J 0
(4400 4200);
DISPLAY 0.510638 (4400 4200);
PAINT SKYBLUE (4400 4200);
FORCEPROP 1 LAST VALUE 120
J 2
(4625 4200);
DISPLAY 0.510638 (4625 4200);
PAINT SKYBLUE (4625 4200);
FORCEPROP 1 LAST PART_NUMBER CS11202FB02
J 0
(4225 4300);
DISPLAY 0.510638 (4225 4300);
PAINT WHITE (4225 4300);
DISPLAY INVISIBLE (4225 4300);
FORCEPROP 1 LAST PACK_TYPE 0402LF
J 0
(4525 4050);
DISPLAY 0.510638 (4525 4050);
PAINT SKYBLUE (4525 4050);
DISPLAY INVISIBLE (4525 4050);
FORCEPROP 1 LAST WATTAGE 1/16W
J 2
(4250 4050);
DISPLAY 0.510638 (4250 4050);
PAINT SKYBLUE (4250 4050);
DISPLAY INVISIBLE (4250 4050);
FORCEPROP 1 LAST PATH I181
J 0
(4225 4350);
DISPLAY 0.978723 (4225 4350);
PAINT WHITE (4225 4350);
DISPLAY INVISIBLE (4225 4350);
FORCEPROP 1 LAST TOLERANCE 1%
J 0
(4275 4100);
DISPLAY 0.510638 (4275 4100);
PAINT SKYBLUE (4275 4100);
DISPLAY INVISIBLE (4275 4100);
FORCEPROP 2 LAST CDS_LIB pure_quanta
J 0
(4275 4200);
DISPLAY INVISIBLE (4275 4200);
FORCEPROP 1 LAST LOCATION R354
J 2
(4150 4200);
DISPLAY 0.702128 (4150 4200);
PAINT YELLOW (4150 4200);
FORCEPROP 1 LASTPIN (4175 4200) $PN 1
J 0
(4187 4212);
DISPLAY 0.808511 (4187 4212);
PAINT WHITE (4187 4212);
FORCEPROP 1 LASTPIN (4375 4200) $PN 2
J 0
(4337 4212);
DISPLAY 0.808511 (4337 4212);
PAINT WHITE (4337 4212);
FORCEPROP 0 LAST $SEC 1
J 0
(4575 4250);
DISPLAY 0.680851 (4575 4250);
PAINT MONO (4575 4250);
DISPLAY INVISIBLE (4575 4250);
FORCEPROP 0 LAST CDS_SEC 1
J 0
(4575 4250);
DISPLAY 1.021277 (4575 4250);
DISPLAY INVISIBLE (4575 4250);
FORCEADD Q_RES..1
(4275 4050);
FORCEPROP 1 LAST MATERIAL CHIP
J 0
(4400 4050);
DISPLAY 0.510638 (4400 4050);
PAINT SKYBLUE (4400 4050);
FORCEPROP 1 LAST VALUE 120
J 2
(4625 4050);
DISPLAY 0.510638 (4625 4050);
PAINT SKYBLUE (4625 4050);
FORCEPROP 1 LAST PART_NUMBER CS11202FB02
J 0
(4225 4150);
DISPLAY 0.510638 (4225 4150);
PAINT WHITE (4225 4150);
DISPLAY INVISIBLE (4225 4150);
FORCEPROP 1 LAST PACK_TYPE 0402LF
J 0
(4525 3900);
DISPLAY 0.510638 (4525 3900);
PAINT SKYBLUE (4525 3900);
DISPLAY INVISIBLE (4525 3900);
FORCEPROP 1 LAST WATTAGE 1/16W
J 2
(4250 3900);
DISPLAY 0.510638 (4250 3900);
PAINT SKYBLUE (4250 3900);
DISPLAY INVISIBLE (4250 3900);
FORCEPROP 1 LAST PATH I182
J 0
(4225 4200);
DISPLAY 0.978723 (4225 4200);
PAINT WHITE (4225 4200);
DISPLAY INVISIBLE (4225 4200);
FORCEPROP 1 LAST TOLERANCE 1%
J 0
(4275 3950);
DISPLAY 0.510638 (4275 3950);
PAINT SKYBLUE (4275 3950);
DISPLAY INVISIBLE (4275 3950);
FORCEPROP 2 LAST CDS_LIB pure_quanta
J 0
(4275 4050);
DISPLAY INVISIBLE (4275 4050);
FORCEPROP 1 LAST LOCATION R355
J 2
(4150 4050);
DISPLAY 0.702128 (4150 4050);
PAINT YELLOW (4150 4050);
FORCEPROP 1 LASTPIN (4175 4050) $PN 1
J 0
(4187 4062);
DISPLAY 0.808511 (4187 4062);
PAINT WHITE (4187 4062);
FORCEPROP 1 LASTPIN (4375 4050) $PN 2
J 0
(4337 4062);
DISPLAY 0.808511 (4337 4062);
PAINT WHITE (4337 4062);
FORCEPROP 0 LAST $SEC 1
J 0
(4575 4100);
DISPLAY 0.680851 (4575 4100);
PAINT MONO (4575 4100);
DISPLAY INVISIBLE (4575 4100);
FORCEPROP 0 LAST CDS_SEC 1
J 0
(4575 4100);
DISPLAY 1.021277 (4575 4100);
DISPLAY INVISIBLE (4575 4100);
FORCEADD Q_RES..1
(4275 4350);
FORCEPROP 1 LAST MATERIAL CHIP
J 0
(4400 4350);
DISPLAY 0.510638 (4400 4350);
PAINT SKYBLUE (4400 4350);
FORCEPROP 1 LAST VALUE 120
J 2
(4625 4350);
DISPLAY 0.510638 (4625 4350);
PAINT SKYBLUE (4625 4350);
FORCEPROP 1 LAST PART_NUMBER CS11202FB02
J 0
(4225 4450);
DISPLAY 0.510638 (4225 4450);
PAINT WHITE (4225 4450);
DISPLAY INVISIBLE (4225 4450);
FORCEPROP 1 LAST PACK_TYPE 0402LF
J 0
(4525 4200);
DISPLAY 0.510638 (4525 4200);
PAINT SKYBLUE (4525 4200);
DISPLAY INVISIBLE (4525 4200);
FORCEPROP 1 LAST WATTAGE 1/16W
J 2
(4250 4200);
DISPLAY 0.510638 (4250 4200);
PAINT SKYBLUE (4250 4200);
DISPLAY INVISIBLE (4250 4200);
FORCEPROP 1 LAST PATH I183
J 0
(4225 4500);
DISPLAY 0.978723 (4225 4500);
PAINT WHITE (4225 4500);
DISPLAY INVISIBLE (4225 4500);
FORCEPROP 1 LAST TOLERANCE 1%
J 0
(4275 4250);
DISPLAY 0.510638 (4275 4250);
PAINT SKYBLUE (4275 4250);
DISPLAY INVISIBLE (4275 4250);
FORCEPROP 2 LAST CDS_LIB pure_quanta
J 0
(4275 4350);
DISPLAY INVISIBLE (4275 4350);
FORCEPROP 1 LAST LOCATION R353
J 2
(4150 4350);
DISPLAY 0.702128 (4150 4350);
PAINT YELLOW (4150 4350);
FORCEPROP 1 LASTPIN (4175 4350) $PN 1
J 0
(4187 4362);
DISPLAY 0.808511 (4187 4362);
PAINT WHITE (4187 4362);
FORCEPROP 1 LASTPIN (4375 4350) $PN 2
J 0
(4337 4362);
DISPLAY 0.808511 (4337 4362);
PAINT WHITE (4337 4362);
FORCEPROP 0 LAST $SEC 1
J 0
(4575 4400);
DISPLAY 0.680851 (4575 4400);
PAINT MONO (4575 4400);
DISPLAY INVISIBLE (4575 4400);
FORCEPROP 0 LAST CDS_SEC 1
J 0
(4575 4400);
DISPLAY 1.021277 (4575 4400);
DISPLAY INVISIBLE (4575 4400);
FORCEADD Q_RES..1
(4275 4500);
FORCEPROP 1 LAST MATERIAL CHIP
J 0
(4400 4500);
DISPLAY 0.510638 (4400 4500);
PAINT SKYBLUE (4400 4500);
FORCEPROP 1 LAST VALUE 120
J 2
(4625 4500);
DISPLAY 0.510638 (4625 4500);
PAINT SKYBLUE (4625 4500);
FORCEPROP 1 LAST PART_NUMBER CS11202FB02
J 0
(4225 4600);
DISPLAY 0.510638 (4225 4600);
PAINT WHITE (4225 4600);
DISPLAY INVISIBLE (4225 4600);
FORCEPROP 1 LAST PACK_TYPE 0402LF
J 0
(4525 4350);
DISPLAY 0.510638 (4525 4350);
PAINT SKYBLUE (4525 4350);
DISPLAY INVISIBLE (4525 4350);
FORCEPROP 1 LAST WATTAGE 1/16W
J 2
(4250 4350);
DISPLAY 0.510638 (4250 4350);
PAINT SKYBLUE (4250 4350);
DISPLAY INVISIBLE (4250 4350);
FORCEPROP 1 LAST PATH I184
J 0
(4225 4650);
DISPLAY 0.978723 (4225 4650);
PAINT WHITE (4225 4650);
DISPLAY INVISIBLE (4225 4650);
FORCEPROP 1 LAST TOLERANCE 1%
J 0
(4275 4400);
DISPLAY 0.510638 (4275 4400);
PAINT SKYBLUE (4275 4400);
DISPLAY INVISIBLE (4275 4400);
FORCEPROP 2 LAST CDS_LIB pure_quanta
J 0
(4275 4500);
DISPLAY INVISIBLE (4275 4500);
FORCEPROP 1 LAST LOCATION R352
J 2
(4150 4500);
DISPLAY 0.702128 (4150 4500);
PAINT YELLOW (4150 4500);
FORCEPROP 1 LASTPIN (4175 4500) $PN 1
J 0
(4187 4512);
DISPLAY 0.808511 (4187 4512);
PAINT WHITE (4187 4512);
FORCEPROP 1 LASTPIN (4375 4500) $PN 2
J 0
(4337 4512);
DISPLAY 0.808511 (4337 4512);
PAINT WHITE (4337 4512);
FORCEPROP 0 LAST $SEC 1
J 0
(4575 4550);
DISPLAY 0.680851 (4575 4550);
PAINT MONO (4575 4550);
DISPLAY INVISIBLE (4575 4550);
FORCEPROP 0 LAST CDS_SEC 1
J 0
(4575 4550);
DISPLAY 1.021277 (4575 4550);
DISPLAY INVISIBLE (4575 4550);
FORCEADD UNIVERSAL_GND..1
(4875 3475);
FORCEPROP 3 LASTPIN (4875 3525) SIG_NAME GND\g
J 0
(4885 3535);
DISPLAY 0.659574 (4885 3535);
PAINT MONO (4885 3535);
DISPLAY INVISIBLE (4885 3535);
FORCEPROP 1 LAST PATH I185
J 0
(4950 3475);
DISPLAY 0.872340 (4950 3475);
PAINT AQUA (4950 3475);
DISPLAY INVISIBLE (4950 3475);
FORCEPROP 1 LAST HDL_POWER GND
J 1
(4900 3400);
DISPLAY 0.702128 (4900 3400);
PAINT GREEN (4900 3400);
DISPLAY INVISIBLE (4900 3400);
FORCEPROP 2 LAST CDS_LIB logical_power
J 0
(4875 3475);
DISPLAY INVISIBLE (4875 3475);
FORCEADD Q_CAP..1
(4875 3650);
FORCEPROP 1 LAST PACK_TYPE 0402
J 0
(4925 3600);
DISPLAY 0.510638 (4925 3600);
PAINT SKYBLUE (4925 3600);
FORCEPROP 1 LAST VOLTAGE 25V
J 0
(4925 3575);
DISPLAY 0.510638 (4925 3575);
PAINT SKYBLUE (4925 3575);
FORCEPROP 1 LAST TOLERANCE 10%
J 0
(4925 3650);
DISPLAY 0.510638 (4925 3650);
PAINT SKYBLUE (4925 3650);
FORCEPROP 1 LAST VALUE 0.1UF
J 0
(4925 3675);
DISPLAY 0.510638 (4925 3675);
PAINT SKYBLUE (4925 3675);
FORCEPROP 1 LAST PART_NUMBER CH4104K1B00
J 0
(4925 3550);
DISPLAY 0.510638 (4925 3550);
PAINT WHITE (4925 3550);
FORCEPROP 1 LAST MATERIAL X7R
J 0
(4925 3625);
DISPLAY 0.510638 (4925 3625);
PAINT SKYBLUE (4925 3625);
FORCEPROP 1 LAST PATH I186
J 0
(4925 3800);
DISPLAY 0.978723 (4925 3800);
PAINT WHITE (4925 3800);
DISPLAY INVISIBLE (4925 3800);
FORCEPROP 2 LAST CDS_LIB pure_quanta
J 0
(4875 3650);
DISPLAY INVISIBLE (4875 3650);
FORCEPROP 2 LAST SEC_TYPE 0402
J 0
(4925 3850);
DISPLAY 0.680851 (4925 3850);
DISPLAY INVISIBLE (4925 3850);
FORCEPROP 1 LAST LOCATION C13
J 0
(4925 3700);
DISPLAY 0.702128 (4925 3700);
PAINT YELLOW (4925 3700);
FORCEPROP 1 LASTPIN (4875 3750) $PN 1
J 0
(4885 3730);
DISPLAY 0.808511 (4885 3730);
PAINT WHITE (4885 3730);
FORCEPROP 1 LASTPIN (4875 3550) $PN 2
J 0
(4885 3530);
DISPLAY 0.808511 (4885 3530);
PAINT WHITE (4885 3530);
FORCEPROP 2 LAST SEC 1
J 0
(4925 3850);
DISPLAY 0.680851 (4925 3850);
PAINT MONO (4925 3850);
DISPLAY INVISIBLE (4925 3850);
FORCEADD Q_CAP..1
(4950 3975);
FORCEPROP 1 LAST PACK_TYPE 0402
J 0
(5000 3925);
DISPLAY 0.510638 (5000 3925);
PAINT SKYBLUE (5000 3925);
FORCEPROP 1 LAST VOLTAGE 25V
J 0
(5000 4000);
DISPLAY 0.510638 (5000 4000);
PAINT SKYBLUE (5000 4000);
FORCEPROP 1 LAST TOLERANCE 10%
J 0
(5000 3975);
DISPLAY 0.510638 (5000 3975);
PAINT SKYBLUE (5000 3975);
FORCEPROP 1 LAST VALUE 0.1UF
J 0
(5000 4025);
DISPLAY 0.510638 (5000 4025);
PAINT SKYBLUE (5000 4025);
FORCEPROP 1 LAST MATERIAL X7R
J 0
(5000 3950);
DISPLAY 0.510638 (5000 3950);
PAINT SKYBLUE (5000 3950);
FORCEPROP 1 LAST PATH I187
J 0
(5000 4125);
DISPLAY 0.978723 (5000 4125);
PAINT WHITE (5000 4125);
DISPLAY INVISIBLE (5000 4125);
FORCEPROP 2 LAST SEC_TYPE 0402
J 0
(5000 4175);
DISPLAY 0.680851 (5000 4175);
DISPLAY INVISIBLE (5000 4175);
FORCEPROP 2 LAST CDS_LIB pure_quanta
J 0
(4950 3975);
DISPLAY INVISIBLE (4950 3975);
FORCEPROP 1 LAST PART_NUMBER CH4104K1B00
J 0
(5000 3825);
DISPLAY 0.510638 (5000 3825);
PAINT WHITE (5000 3825);
DISPLAY INVISIBLE (5000 3825);
FORCEPROP 1 LAST LOCATION C14
J 0
(5000 4050);
DISPLAY 0.702128 (5000 4050);
PAINT YELLOW (5000 4050);
FORCEPROP 1 LASTPIN (4950 4075) $PN 1
J 0
(4960 4055);
DISPLAY 0.808511 (4960 4055);
PAINT WHITE (4960 4055);
FORCEPROP 1 LASTPIN (4950 3875) $PN 2
J 0
(4960 3855);
DISPLAY 0.808511 (4960 3855);
PAINT WHITE (4960 3855);
FORCEPROP 2 LAST SEC 1
J 0
(5000 4175);
DISPLAY 0.680851 (5000 4175);
PAINT MONO (5000 4175);
DISPLAY INVISIBLE (5000 4175);
FORCEADD UNIVERSAL_GND..1
(4950 3800);
FORCEPROP 3 LASTPIN (4950 3850) SIG_NAME GND\g
J 0
(4960 3860);
DISPLAY 0.659574 (4960 3860);
PAINT MONO (4960 3860);
DISPLAY INVISIBLE (4960 3860);
FORCEPROP 1 LAST PATH I188
J 0
(5025 3800);
DISPLAY 0.872340 (5025 3800);
PAINT AQUA (5025 3800);
DISPLAY INVISIBLE (5025 3800);
FORCEPROP 1 LAST HDL_POWER GND
J 1
(4975 3725);
DISPLAY 0.702128 (4975 3725);
PAINT GREEN (4975 3725);
DISPLAY INVISIBLE (4975 3725);
FORCEPROP 2 LAST CDS_LIB logical_power
J 0
(4950 3800);
DISPLAY INVISIBLE (4950 3800);
FORCEADD UNIVERSAL_GND..1
(5025 4100);
FORCEPROP 3 LASTPIN (5025 4150) SIG_NAME GND\g
J 0
(5035 4160);
DISPLAY 0.659574 (5035 4160);
PAINT MONO (5035 4160);
DISPLAY INVISIBLE (5035 4160);
FORCEPROP 1 LAST PATH I189
J 0
(5100 4100);
DISPLAY 0.872340 (5100 4100);
PAINT AQUA (5100 4100);
DISPLAY INVISIBLE (5100 4100);
FORCEPROP 1 LAST HDL_POWER GND
J 1
(5050 4025);
DISPLAY 0.702128 (5050 4025);
PAINT GREEN (5050 4025);
DISPLAY INVISIBLE (5050 4025);
FORCEPROP 2 LAST CDS_LIB logical_power
J 0
(5025 4100);
DISPLAY INVISIBLE (5025 4100);
FORCEADD Q_CAP..1
(-3050 1300);
FORCEPROP 1 LAST VOLTAGE 25V
J 0
(-3000 1300);
DISPLAY 0.510638 (-3000 1300);
PAINT SKYBLUE (-3000 1300);
FORCEPROP 1 LAST VALUE 0.1UF
J 0
(-3000 1350);
DISPLAY 0.510638 (-3000 1350);
PAINT SKYBLUE (-3000 1350);
FORCEPROP 1 LAST TOLERANCE 10%
J 0
(-3000 1250);
DISPLAY 0.510638 (-3000 1250);
PAINT SKYBLUE (-3000 1250);
FORCEPROP 1 LAST MATERIAL X7R
J 0
(-3000 1200);
DISPLAY 0.510638 (-3000 1200);
PAINT SKYBLUE (-3000 1200);
FORCEPROP 1 LAST PACK_TYPE 0402
J 0
(-3000 1150);
DISPLAY 0.510638 (-3000 1150);
PAINT SKYBLUE (-3000 1150);
FORCEPROP 1 LAST PATH I19
J 0
(-3000 1450);
DISPLAY 0.978723 (-3000 1450);
PAINT WHITE (-3000 1450);
DISPLAY INVISIBLE (-3000 1450);
FORCEPROP 2 LAST SEC_TYPE 0402
J 0
(-3000 1500);
DISPLAY 0.680851 (-3000 1500);
DISPLAY INVISIBLE (-3000 1500);
FORCEPROP 2 LAST CDS_LIB pure_quanta
J 0
(-3050 1300);
DISPLAY INVISIBLE (-3050 1300);
FORCEPROP 1 LAST PART_NUMBER CH4104K1B00
J 0
(-3000 1100);
DISPLAY 0.510638 (-3000 1100);
PAINT WHITE (-3000 1100);
DISPLAY INVISIBLE (-3000 1100);
FORCEPROP 1 LAST LOCATION C6
J 0
(-3000 1400);
DISPLAY 0.702128 (-3000 1400);
PAINT YELLOW (-3000 1400);
FORCEPROP 1 LASTPIN (-3050 1400) $PN 1
J 0
(-3040 1380);
DISPLAY 0.808511 (-3040 1380);
PAINT WHITE (-3040 1380);
FORCEPROP 1 LASTPIN (-3050 1200) $PN 2
J 0
(-3040 1180);
DISPLAY 0.808511 (-3040 1180);
PAINT WHITE (-3040 1180);
FORCEPROP 2 LAST SEC 1
J 0
(-3000 1500);
DISPLAY 0.680851 (-3000 1500);
PAINT MONO (-3000 1500);
DISPLAY INVISIBLE (-3000 1500);
FORCEADD Q_CAP..1
(5025 4275);
FORCEPROP 1 LAST PACK_TYPE 0402
J 0
(5075 4250);
DISPLAY 0.510638 (5075 4250);
PAINT SKYBLUE (5075 4250);
FORCEPROP 1 LAST VOLTAGE 25V
J 0
(5075 4325);
DISPLAY 0.510638 (5075 4325);
PAINT SKYBLUE (5075 4325);
FORCEPROP 1 LAST TOLERANCE 10%
J 0
(5075 4300);
DISPLAY 0.510638 (5075 4300);
PAINT SKYBLUE (5075 4300);
FORCEPROP 1 LAST VALUE 0.1UF
J 0
(5075 4350);
DISPLAY 0.510638 (5075 4350);
PAINT SKYBLUE (5075 4350);
FORCEPROP 1 LAST MATERIAL X7R
J 0
(5075 4275);
DISPLAY 0.510638 (5075 4275);
PAINT SKYBLUE (5075 4275);
FORCEPROP 1 LAST PATH I190
J 0
(5075 4425);
DISPLAY 0.978723 (5075 4425);
PAINT WHITE (5075 4425);
DISPLAY INVISIBLE (5075 4425);
FORCEPROP 2 LAST CDS_LIB pure_quanta
J 0
(5025 4275);
DISPLAY INVISIBLE (5025 4275);
FORCEPROP 2 LAST SEC_TYPE 0402
J 0
(5075 4475);
DISPLAY 0.680851 (5075 4475);
DISPLAY INVISIBLE (5075 4475);
FORCEPROP 1 LAST PART_NUMBER CH4104K1B00
J 0
(5075 4125);
DISPLAY 0.510638 (5075 4125);
PAINT WHITE (5075 4125);
DISPLAY INVISIBLE (5075 4125);
FORCEPROP 1 LAST LOCATION C17
J 0
(5075 4375);
DISPLAY 0.702128 (5075 4375);
PAINT YELLOW (5075 4375);
FORCEPROP 1 LASTPIN (5025 4375) $PN 1
J 0
(5035 4355);
DISPLAY 0.808511 (5035 4355);
PAINT WHITE (5035 4355);
FORCEPROP 1 LASTPIN (5025 4175) $PN 2
J 0
(5035 4155);
DISPLAY 0.808511 (5035 4155);
PAINT WHITE (5035 4155);
FORCEPROP 2 LAST SEC 1
J 0
(5075 4475);
DISPLAY 0.680851 (5075 4475);
PAINT MONO (5075 4475);
DISPLAY INVISIBLE (5075 4475);
FORCEADD UNIVERSAL_GND..1
(5175 4425);
FORCEPROP 3 LASTPIN (5175 4475) SIG_NAME GND\g
J 0
(5185 4485);
DISPLAY 0.659574 (5185 4485);
PAINT MONO (5185 4485);
DISPLAY INVISIBLE (5185 4485);
FORCEPROP 1 LAST PATH I191
J 0
(5250 4425);
DISPLAY 0.872340 (5250 4425);
PAINT AQUA (5250 4425);
DISPLAY INVISIBLE (5250 4425);
FORCEPROP 1 LAST HDL_POWER GND
J 1
(5200 4350);
DISPLAY 0.702128 (5200 4350);
PAINT GREEN (5200 4350);
DISPLAY INVISIBLE (5200 4350);
FORCEPROP 2 LAST CDS_LIB logical_power
J 0
(5175 4425);
DISPLAY INVISIBLE (5175 4425);
FORCEADD Q_CAP..1
(5175 4600);
FORCEPROP 1 LAST PACK_TYPE 0402
J 0
(5225 4575);
DISPLAY 0.510638 (5225 4575);
PAINT SKYBLUE (5225 4575);
FORCEPROP 1 LAST VOLTAGE 25V
J 0
(5225 4650);
DISPLAY 0.510638 (5225 4650);
PAINT SKYBLUE (5225 4650);
FORCEPROP 1 LAST TOLERANCE 10%
J 0
(5225 4625);
DISPLAY 0.510638 (5225 4625);
PAINT SKYBLUE (5225 4625);
FORCEPROP 1 LAST VALUE 0.1UF
J 0
(5225 4675);
DISPLAY 0.510638 (5225 4675);
PAINT SKYBLUE (5225 4675);
FORCEPROP 1 LAST MATERIAL X7R
J 0
(5225 4600);
DISPLAY 0.510638 (5225 4600);
PAINT SKYBLUE (5225 4600);
FORCEPROP 1 LAST PATH I192
J 0
(5225 4750);
DISPLAY 0.978723 (5225 4750);
PAINT WHITE (5225 4750);
DISPLAY INVISIBLE (5225 4750);
FORCEPROP 2 LAST CDS_LIB pure_quanta
J 0
(5175 4600);
DISPLAY INVISIBLE (5175 4600);
FORCEPROP 2 LAST SEC_TYPE 0402
J 0
(5225 4800);
DISPLAY 0.680851 (5225 4800);
DISPLAY INVISIBLE (5225 4800);
FORCEPROP 1 LAST PART_NUMBER CH4104K1B00
J 0
(5225 4450);
DISPLAY 0.510638 (5225 4450);
PAINT WHITE (5225 4450);
DISPLAY INVISIBLE (5225 4450);
FORCEPROP 1 LAST LOCATION C18
J 0
(5225 4700);
DISPLAY 0.702128 (5225 4700);
PAINT YELLOW (5225 4700);
FORCEPROP 1 LASTPIN (5175 4700) $PN 1
J 0
(5185 4680);
DISPLAY 0.808511 (5185 4680);
PAINT WHITE (5185 4680);
FORCEPROP 1 LASTPIN (5175 4500) $PN 2
J 0
(5185 4480);
DISPLAY 0.808511 (5185 4480);
PAINT WHITE (5185 4480);
FORCEPROP 2 LAST SEC 1
J 0
(5225 4800);
DISPLAY 0.680851 (5225 4800);
PAINT MONO (5225 4800);
DISPLAY INVISIBLE (5225 4800);
FORCEADD Q_RES..1
(3600 4650);
FORCEPROP 1 LAST MATERIAL CHIP
J 0
(3725 4650);
DISPLAY 0.510638 (3725 4650);
PAINT SKYBLUE (3725 4650);
FORCEPROP 1 LAST VALUE 120
J 2
(3925 4650);
DISPLAY 0.510638 (3925 4650);
PAINT SKYBLUE (3925 4650);
FORCEPROP 1 LAST PART_NUMBER CS11202FB02
J 0
(3550 4750);
DISPLAY 0.510638 (3550 4750);
PAINT WHITE (3550 4750);
DISPLAY INVISIBLE (3550 4750);
FORCEPROP 1 LAST PACK_TYPE 0402LF
J 0
(3850 4500);
DISPLAY 0.510638 (3850 4500);
PAINT SKYBLUE (3850 4500);
DISPLAY INVISIBLE (3850 4500);
FORCEPROP 1 LAST WATTAGE 1/16W
J 2
(3575 4500);
DISPLAY 0.510638 (3575 4500);
PAINT SKYBLUE (3575 4500);
DISPLAY INVISIBLE (3575 4500);
FORCEPROP 1 LAST PATH I193
J 0
(3550 4800);
DISPLAY 0.978723 (3550 4800);
PAINT WHITE (3550 4800);
DISPLAY INVISIBLE (3550 4800);
FORCEPROP 1 LAST TOLERANCE 1%
J 0
(3600 4550);
DISPLAY 0.510638 (3600 4550);
PAINT SKYBLUE (3600 4550);
DISPLAY INVISIBLE (3600 4550);
FORCEPROP 2 LAST CDS_LIB pure_quanta
J 0
(3600 4650);
DISPLAY INVISIBLE (3600 4650);
FORCEPROP 1 LAST LOCATION R326
J 2
(3475 4650);
DISPLAY 0.702128 (3475 4650);
PAINT YELLOW (3475 4650);
FORCEPROP 1 LASTPIN (3500 4650) $PN 1
J 0
(3512 4662);
DISPLAY 0.808511 (3512 4662);
PAINT WHITE (3512 4662);
FORCEPROP 1 LASTPIN (3700 4650) $PN 2
J 0
(3662 4662);
DISPLAY 0.808511 (3662 4662);
PAINT WHITE (3662 4662);
FORCEPROP 0 LAST $SEC 1
J 0
(3900 4700);
DISPLAY 0.680851 (3900 4700);
PAINT MONO (3900 4700);
DISPLAY INVISIBLE (3900 4700);
FORCEPROP 0 LAST CDS_SEC 1
J 0
(3900 4700);
DISPLAY 1.021277 (3900 4700);
DISPLAY INVISIBLE (3900 4700);
FORCEADD Q_RES..1
(4275 4650);
FORCEPROP 1 LAST PART_NUMBER CS11202FB02
J 0
(4100 4800);
DISPLAY 0.510638 (4100 4800);
PAINT WHITE (4100 4800);
FORCEPROP 1 LAST PACK_TYPE 0402LF
J 0
(4050 4725);
DISPLAY 0.510638 (4050 4725);
PAINT SKYBLUE (4050 4725);
FORCEPROP 1 LAST MATERIAL CHIP
J 0
(4400 4650);
DISPLAY 0.510638 (4400 4650);
PAINT SKYBLUE (4400 4650);
FORCEPROP 1 LAST WATTAGE 1/16W
J 2
(4500 4725);
DISPLAY 0.510638 (4500 4725);
PAINT SKYBLUE (4500 4725);
FORCEPROP 1 LAST TOLERANCE 1%
J 0
(4550 4725);
DISPLAY 0.510638 (4550 4725);
PAINT SKYBLUE (4550 4725);
FORCEPROP 1 LAST VALUE 120
J 2
(4625 4650);
DISPLAY 0.510638 (4625 4650);
PAINT SKYBLUE (4625 4650);
FORCEPROP 1 LAST PATH I194
J 0
(4225 4800);
DISPLAY 0.978723 (4225 4800);
PAINT WHITE (4225 4800);
DISPLAY INVISIBLE (4225 4800);
FORCEPROP 2 LAST CDS_LIB pure_quanta
J 0
(4275 4650);
DISPLAY INVISIBLE (4275 4650);
FORCEPROP 1 LAST LOCATION R351
J 2
(4150 4650);
DISPLAY 0.702128 (4150 4650);
PAINT YELLOW (4150 4650);
FORCEPROP 1 LASTPIN (4175 4650) $PN 1
J 0
(4187 4662);
DISPLAY 0.808511 (4187 4662);
PAINT WHITE (4187 4662);
FORCEPROP 1 LASTPIN (4375 4650) $PN 2
J 0
(4337 4662);
DISPLAY 0.808511 (4337 4662);
PAINT WHITE (4337 4662);
FORCEPROP 0 LAST $SEC 1
J 0
(4575 4700);
DISPLAY 0.680851 (4575 4700);
PAINT MONO (4575 4700);
DISPLAY INVISIBLE (4575 4700);
FORCEPROP 0 LAST CDS_SEC 1
J 0
(4575 4700);
DISPLAY 1.021277 (4575 4700);
DISPLAY INVISIBLE (4575 4700);
FORCEADD UNIVERSAL_POWER..1
(4725 4850);
FORCEPROP 3 LASTPIN (4725 4800) SIG_NAME P1V2_AUX\g
J 0
(4735 4810);
DISPLAY 0.659574 (4735 4810);
PAINT MONO (4735 4810);
DISPLAY INVISIBLE (4735 4810);
FORCEPROP 1 LAST HDL_POWER P1V2_AUX
J 1
(4775 4900);
DISPLAY 0.702128 (4775 4900);
PAINT GREEN (4775 4900);
FORCEPROP 1 LAST PATH I195
J 0
(4775 4875);
DISPLAY 0.872340 (4775 4875);
PAINT AQUA (4775 4875);
DISPLAY INVISIBLE (4775 4875);
FORCEPROP 2 LAST CDS_LIB logical_power
J 0
(4725 4850);
DISPLAY INVISIBLE (4725 4850);
FORCEADD K4A8G165WCBCTD..1
(-1075 3100);
FORCEPROP 1 LAST MATERIAL IC
J 0
(-1445 4632);
DISPLAY 0.510638 (-1445 4632);
PAINT SKYBLUE (-1445 4632);
FORCEPROP 1 LAST PART_NUMBER AKD5FGUT502
J 0
(-1445 4759);
DISPLAY 0.510638 (-1445 4759);
PAINT WHITE (-1445 4759);
FORCEPROP 2 LAST VALUE K4A8G165WC-BCTD
J 0
(-1325 4625);
DISPLAY 0.510638 (-1325 4625);
PAINT SKYBLUE (-1325 4625);
FORCEPROP 2 LAST PART_TYPE SMLF
J 0
(-1325 4675);
DISPLAY 0.510638 (-1325 4675);
PAINT SKYBLUE (-1325 4675);
FORCEPROP 1 LAST PATH I196
J 0
(-1075 3100);
DISPLAY 0.723404 (-1075 3100);
PAINT GREEN (-1075 3100);
DISPLAY INVISIBLE (-1075 3100);
FORCEPROP 1 LAST CDS_LMAN_SYM_OUTLINE -375,1500,375,-1500
J 0
(-1075 3100);
DISPLAY 0.468085 (-1075 3100);
PAINT GREEN (-1075 3100);
DISPLAY INVISIBLE (-1075 3100);
FORCEPROP 1 LAST NEEDS_NO_SIZE TRUE
J 0
(-1075 3100);
DISPLAY 0.723404 (-1075 3100);
PAINT GREEN (-1075 3100);
DISPLAY INVISIBLE (-1075 3100);
FORCEPROP 2 LAST CDS_LIB pure_quanta
J 0
(-1075 3100);
DISPLAY INVISIBLE (-1075 3100);
FORCEPROP 1 LAST LOCATION U1
J 0
(-1445 4906);
DISPLAY 0.702128 (-1445 4906);
PAINT AQUA (-1445 4906);
FORCEPROP 0 LASTPIN (-1600 3750) $PN P3
J 2
(-1610 3760);
DISPLAY 0.680851 (-1610 3760);
PAINT MONO (-1610 3760);
FORCEPROP 0 LASTPIN (-1600 3700) $PN P7
J 2
(-1610 3710);
DISPLAY 0.680851 (-1610 3710);
PAINT MONO (-1610 3710);
FORCEPROP 0 LASTPIN (-1600 3650) $PN R3
J 2
(-1610 3660);
DISPLAY 0.680851 (-1610 3660);
PAINT MONO (-1610 3660);
FORCEPROP 0 LASTPIN (-1600 3600) $PN N7
J 2
(-1610 3610);
DISPLAY 0.680851 (-1610 3610);
PAINT MONO (-1610 3610);
FORCEPROP 0 LASTPIN (-1600 3550) $PN N3
J 2
(-1610 3560);
DISPLAY 0.680851 (-1610 3560);
PAINT MONO (-1610 3560);
FORCEPROP 0 LASTPIN (-1600 3500) $PN P8
J 2
(-1610 3510);
DISPLAY 0.680851 (-1610 3510);
PAINT MONO (-1610 3510);
FORCEPROP 0 LASTPIN (-1600 3450) $PN P2
J 2
(-1610 3460);
DISPLAY 0.680851 (-1610 3460);
PAINT MONO (-1610 3460);
FORCEPROP 0 LASTPIN (-1600 3400) $PN R8
J 2
(-1610 3410);
DISPLAY 0.680851 (-1610 3410);
PAINT MONO (-1610 3410);
FORCEPROP 0 LASTPIN (-1600 3350) $PN R2
J 2
(-1610 3360);
DISPLAY 0.680851 (-1610 3360);
PAINT MONO (-1610 3360);
FORCEPROP 0 LASTPIN (-1600 3300) $PN R7
J 2
(-1610 3310);
DISPLAY 0.680851 (-1610 3310);
PAINT MONO (-1610 3310);
FORCEPROP 0 LASTPIN (-1600 3250) $PN M3
J 2
(-1610 3260);
DISPLAY 0.680851 (-1610 3260);
PAINT MONO (-1610 3260);
FORCEPROP 0 LASTPIN (-1600 3200) $PN T2
J 2
(-1610 3210);
DISPLAY 0.680851 (-1610 3210);
PAINT MONO (-1610 3210);
FORCEPROP 0 LASTPIN (-1600 3150) $PN M7
J 2
(-1610 3160);
DISPLAY 0.680851 (-1610 3160);
PAINT MONO (-1610 3160);
FORCEPROP 0 LASTPIN (-1600 3100) $PN T8
J 2
(-1610 3110);
DISPLAY 0.680851 (-1610 3110);
PAINT MONO (-1610 3110);
FORCEPROP 0 LASTPIN (-1600 4200) $PN L3
J 2
(-1610 4210);
DISPLAY 0.680851 (-1610 4210);
PAINT MONO (-1610 4210);
FORCEPROP 0 LASTPIN (-550 3050) $PN P9
J 0
(-540 3060);
DISPLAY 0.680851 (-540 3060);
PAINT MONO (-540 3060);
FORCEPROP 0 LASTPIN (-1600 3900) $PN N2
J 2
(-1610 3910);
DISPLAY 0.680851 (-1610 3910);
PAINT MONO (-1610 3910);
FORCEPROP 0 LASTPIN (-1600 3850) $PN N8
J 2
(-1610 3860);
DISPLAY 0.680851 (-1610 3860);
PAINT MONO (-1610 3860);
FORCEPROP 0 LASTPIN (-1600 3950) $PN M2
J 2
(-1610 3960);
DISPLAY 0.680851 (-1610 3960);
PAINT MONO (-1610 3960);
FORCEPROP 0 LASTPIN (-1600 4400) $PN M8
J 2
(-1610 4410);
DISPLAY 0.680851 (-1610 4410);
PAINT MONO (-1610 4410);
FORCEPROP 0 LASTPIN (-550 3450) $PN K8
J 0
(-540 3460);
DISPLAY 0.680851 (-540 3460);
PAINT MONO (-540 3460);
FORCEPROP 0 LASTPIN (-550 3500) $PN K7
J 0
(-540 3510);
DISPLAY 0.680851 (-540 3510);
PAINT MONO (-540 3510);
FORCEPROP 0 LASTPIN (-1600 4300) $PN K2
J 2
(-1610 4310);
DISPLAY 0.680851 (-1610 4310);
PAINT MONO (-1610 4310);
FORCEPROP 0 LASTPIN (-1600 4500) $PN L7
J 2
(-1610 4510);
DISPLAY 0.680851 (-1610 4510);
PAINT MONO (-1610 4510);
FORCEPROP 0 LASTPIN (-550 3650) $PN E7
J 0
(-540 3660);
DISPLAY 0.680851 (-540 3660);
PAINT MONO (-540 3660);
FORCEPROP 0 LASTPIN (-550 3700) $PN E2
J 0
(-540 3710);
DISPLAY 0.680851 (-540 3710);
PAINT MONO (-540 3710);
FORCEPROP 0 LASTPIN (-550 4500) $PN G2
J 0
(-540 4510);
DISPLAY 0.680851 (-540 4510);
PAINT MONO (-540 4510);
FORCEPROP 0 LASTPIN (-550 4450) $PN F7
J 0
(-540 4460);
DISPLAY 0.680851 (-540 4460);
PAINT MONO (-540 4460);
FORCEPROP 0 LASTPIN (-550 4400) $PN H3
J 0
(-540 4410);
DISPLAY 0.680851 (-540 4410);
PAINT MONO (-540 4410);
FORCEPROP 0 LASTPIN (-550 4350) $PN H7
J 0
(-540 4360);
DISPLAY 0.680851 (-540 4360);
PAINT MONO (-540 4360);
FORCEPROP 0 LASTPIN (-550 4300) $PN H2
J 0
(-540 4310);
DISPLAY 0.680851 (-540 4310);
PAINT MONO (-540 4310);
FORCEPROP 0 LASTPIN (-550 4250) $PN H8
J 0
(-540 4260);
DISPLAY 0.680851 (-540 4260);
PAINT MONO (-540 4260);
FORCEPROP 0 LASTPIN (-550 4200) $PN J3
J 0
(-540 4210);
DISPLAY 0.680851 (-540 4210);
PAINT MONO (-540 4210);
FORCEPROP 0 LASTPIN (-550 4150) $PN J7
J 0
(-540 4160);
DISPLAY 0.680851 (-540 4160);
PAINT MONO (-540 4160);
FORCEPROP 0 LASTPIN (-550 3250) $PN F3
J 0
(-540 3260);
DISPLAY 0.680851 (-540 3260);
PAINT MONO (-540 3260);
FORCEPROP 0 LASTPIN (-550 3300) $PN G3
J 0
(-540 3310);
DISPLAY 0.680851 (-540 3310);
PAINT MONO (-540 3310);
FORCEPROP 0 LASTPIN (-550 3350) $PN A7
J 0
(-540 3360);
DISPLAY 0.680851 (-540 3360);
PAINT MONO (-540 3360);
FORCEPROP 0 LASTPIN (-550 3400) $PN B7
J 0
(-540 3410);
DISPLAY 0.680851 (-540 3410);
PAINT MONO (-540 3410);
FORCEPROP 0 LASTPIN (-550 4100) $PN A3
J 0
(-540 4110);
DISPLAY 0.680851 (-540 4110);
PAINT MONO (-540 4110);
FORCEPROP 0 LASTPIN (-550 4050) $PN B8
J 0
(-540 4060);
DISPLAY 0.680851 (-540 4060);
PAINT MONO (-540 4060);
FORCEPROP 0 LASTPIN (-550 4000) $PN C3
J 0
(-540 4010);
DISPLAY 0.680851 (-540 4010);
PAINT MONO (-540 4010);
FORCEPROP 0 LASTPIN (-550 3950) $PN C7
J 0
(-540 3960);
DISPLAY 0.680851 (-540 3960);
PAINT MONO (-540 3960);
FORCEPROP 0 LASTPIN (-550 3900) $PN C2
J 0
(-540 3910);
DISPLAY 0.680851 (-540 3910);
PAINT MONO (-540 3910);
FORCEPROP 0 LASTPIN (-550 3850) $PN C8
J 0
(-540 3860);
DISPLAY 0.680851 (-540 3860);
PAINT MONO (-540 3860);
FORCEPROP 0 LASTPIN (-550 3800) $PN D3
J 0
(-540 3810);
DISPLAY 0.680851 (-540 3810);
PAINT MONO (-540 3810);
FORCEPROP 0 LASTPIN (-550 3750) $PN D7
J 0
(-540 3760);
DISPLAY 0.680851 (-540 3760);
PAINT MONO (-540 3760);
FORCEPROP 0 LASTPIN (-550 2700) $PN T7
J 0
(-540 2710);
DISPLAY 0.680851 (-540 2710);
PAINT MONO (-540 2710);
FORCEPROP 0 LASTPIN (-1600 4250) $PN K3
J 2
(-1610 4260);
DISPLAY 0.680851 (-1610 4260);
PAINT MONO (-1610 4260);
FORCEPROP 0 LASTPIN (-550 2950) $PN T3
J 0
(-540 2960);
DISPLAY 0.680851 (-540 2960);
PAINT MONO (-540 2960);
FORCEPROP 0 LASTPIN (-1600 4450) $PN L8
J 2
(-1610 4460);
DISPLAY 0.680851 (-1610 4460);
PAINT MONO (-1610 4460);
FORCEPROP 0 LASTPIN (-1600 2900) $PN P1
J 2
(-1610 2910);
DISPLAY 0.680851 (-1610 2910);
PAINT MONO (-1610 2910);
FORCEPROP 0 LASTPIN (-550 3000) $PN N9
J 0
(-540 3010);
DISPLAY 0.680851 (-540 3010);
PAINT MONO (-540 3010);
FORCEPROP 0 LASTPIN (-1600 2750) $PN B3
J 2
(-1610 2760);
DISPLAY 0.680851 (-1610 2760);
PAINT MONO (-1610 2760);
FORCEPROP 0 LASTPIN (-1600 2700) $PN B9
J 2
(-1610 2710);
DISPLAY 0.680851 (-1610 2710);
PAINT MONO (-1610 2710);
FORCEPROP 0 LASTPIN (-1600 2650) $PN D1
J 2
(-1610 2660);
DISPLAY 0.680851 (-1610 2660);
PAINT MONO (-1610 2660);
FORCEPROP 0 LASTPIN (-1600 2600) $PN G7
J 2
(-1610 2610);
DISPLAY 0.680851 (-1610 2610);
PAINT MONO (-1610 2610);
FORCEPROP 0 LASTPIN (-1600 2550) $PN J1
J 2
(-1610 2560);
DISPLAY 0.680851 (-1610 2560);
PAINT MONO (-1610 2560);
FORCEPROP 0 LASTPIN (-1600 2500) $PN J9
J 2
(-1610 2510);
DISPLAY 0.680851 (-1610 2510);
PAINT MONO (-1610 2510);
FORCEPROP 0 LASTPIN (-1600 2450) $PN L1
J 2
(-1610 2460);
DISPLAY 0.680851 (-1610 2460);
PAINT MONO (-1610 2460);
FORCEPROP 0 LASTPIN (-1600 2400) $PN L9
J 2
(-1610 2410);
DISPLAY 0.680851 (-1610 2410);
PAINT MONO (-1610 2410);
FORCEPROP 0 LASTPIN (-1600 2350) $PN R1
J 2
(-1610 2360);
DISPLAY 0.680851 (-1610 2360);
PAINT MONO (-1610 2360);
FORCEPROP 0 LASTPIN (-1600 2300) $PN T9
J 2
(-1610 2310);
DISPLAY 0.680851 (-1610 2310);
PAINT MONO (-1610 2310);
FORCEPROP 0 LASTPIN (-1600 2250) $PN A1
J 2
(-1610 2260);
DISPLAY 0.680851 (-1610 2260);
PAINT MONO (-1610 2260);
FORCEPROP 0 LASTPIN (-1600 2200) $PN A9
J 2
(-1610 2210);
DISPLAY 0.680851 (-1610 2210);
PAINT MONO (-1610 2210);
FORCEPROP 0 LASTPIN (-1600 2150) $PN C1
J 2
(-1610 2160);
DISPLAY 0.680851 (-1610 2160);
PAINT MONO (-1610 2160);
FORCEPROP 0 LASTPIN (-1600 2100) $PN D9
J 2
(-1610 2110);
DISPLAY 0.680851 (-1610 2110);
PAINT MONO (-1610 2110);
FORCEPROP 0 LASTPIN (-1600 2050) $PN F2
J 2
(-1610 2060);
DISPLAY 0.680851 (-1610 2060);
PAINT MONO (-1610 2060);
FORCEPROP 0 LASTPIN (-1600 2000) $PN F8
J 2
(-1610 2010);
DISPLAY 0.680851 (-1610 2010);
PAINT MONO (-1610 2010);
FORCEPROP 0 LASTPIN (-1600 1950) $PN G1
J 2
(-1610 1960);
DISPLAY 0.680851 (-1610 1960);
PAINT MONO (-1610 1960);
FORCEPROP 0 LASTPIN (-1600 1900) $PN G9
J 2
(-1610 1910);
DISPLAY 0.680851 (-1610 1910);
PAINT MONO (-1610 1910);
FORCEPROP 0 LASTPIN (-1600 1850) $PN J2
J 2
(-1610 1860);
DISPLAY 0.680851 (-1610 1860);
PAINT MONO (-1610 1860);
FORCEPROP 0 LASTPIN (-1600 1800) $PN J8
J 2
(-1610 1810);
DISPLAY 0.680851 (-1610 1810);
PAINT MONO (-1610 1810);
FORCEPROP 0 LASTPIN (-1600 1750) $PN B1
J 2
(-1610 1760);
DISPLAY 0.680851 (-1610 1760);
PAINT MONO (-1610 1760);
FORCEPROP 0 LASTPIN (-1600 1700) $PN R9
J 2
(-1610 1710);
DISPLAY 0.680851 (-1610 1710);
PAINT MONO (-1610 1710);
FORCEPROP 0 LASTPIN (-550 2800) $PN M1
J 0
(-540 2810);
DISPLAY 0.680851 (-540 2810);
PAINT MONO (-540 2810);
FORCEPROP 0 LASTPIN (-550 2600) $PN B2
J 0
(-540 2610);
DISPLAY 0.680851 (-540 2610);
PAINT MONO (-540 2610);
FORCEPROP 0 LASTPIN (-550 2550) $PN E1
J 0
(-540 2560);
DISPLAY 0.680851 (-540 2560);
PAINT MONO (-540 2560);
FORCEPROP 0 LASTPIN (-550 2500) $PN E9
J 0
(-540 2510);
DISPLAY 0.680851 (-540 2510);
PAINT MONO (-540 2510);
FORCEPROP 0 LASTPIN (-550 2450) $PN G8
J 0
(-540 2460);
DISPLAY 0.680851 (-540 2460);
PAINT MONO (-540 2460);
FORCEPROP 0 LASTPIN (-550 2400) $PN K1
J 0
(-540 2410);
DISPLAY 0.680851 (-540 2410);
PAINT MONO (-540 2410);
FORCEPROP 0 LASTPIN (-550 2350) $PN K9
J 0
(-540 2360);
DISPLAY 0.680851 (-540 2360);
PAINT MONO (-540 2360);
FORCEPROP 0 LASTPIN (-550 2300) $PN M9
J 0
(-540 2310);
DISPLAY 0.680851 (-540 2310);
PAINT MONO (-540 2310);
FORCEPROP 0 LASTPIN (-550 2250) $PN N1
J 0
(-540 2260);
DISPLAY 0.680851 (-540 2260);
PAINT MONO (-540 2260);
FORCEPROP 0 LASTPIN (-550 2200) $PN T1
J 0
(-540 2210);
DISPLAY 0.680851 (-540 2210);
PAINT MONO (-540 2210);
FORCEPROP 0 LASTPIN (-550 2150) $PN A2
J 0
(-540 2160);
DISPLAY 0.680851 (-540 2160);
PAINT MONO (-540 2160);
FORCEPROP 0 LASTPIN (-550 2100) $PN A8
J 0
(-540 2110);
DISPLAY 0.680851 (-540 2110);
PAINT MONO (-540 2110);
FORCEPROP 0 LASTPIN (-550 2050) $PN C9
J 0
(-540 2060);
DISPLAY 0.680851 (-540 2060);
PAINT MONO (-540 2060);
FORCEPROP 0 LASTPIN (-550 2000) $PN D2
J 0
(-540 2010);
DISPLAY 0.680851 (-540 2010);
PAINT MONO (-540 2010);
FORCEPROP 0 LASTPIN (-550 1950) $PN D8
J 0
(-540 1960);
DISPLAY 0.680851 (-540 1960);
PAINT MONO (-540 1960);
FORCEPROP 0 LASTPIN (-550 1900) $PN E3
J 0
(-540 1910);
DISPLAY 0.680851 (-540 1910);
PAINT MONO (-540 1910);
FORCEPROP 0 LASTPIN (-550 1850) $PN E8
J 0
(-540 1860);
DISPLAY 0.680851 (-540 1860);
PAINT MONO (-540 1860);
FORCEPROP 0 LASTPIN (-550 1800) $PN F1
J 0
(-540 1810);
DISPLAY 0.680851 (-540 1810);
PAINT MONO (-540 1810);
FORCEPROP 0 LASTPIN (-550 1750) $PN H1
J 0
(-540 1760);
DISPLAY 0.680851 (-540 1760);
PAINT MONO (-540 1760);
FORCEPROP 0 LASTPIN (-550 1700) $PN H9
J 0
(-540 1710);
DISPLAY 0.680851 (-540 1710);
PAINT MONO (-540 1710);
FORCEPROP 0 LASTPIN (-1600 4350) $PN L2
J 2
(-1610 4360);
DISPLAY 0.680851 (-1610 4360);
PAINT MONO (-1610 4360);
FORCEPROP 0 LASTPIN (-550 3100) $PN F9
J 0
(-540 3110);
DISPLAY 0.680851 (-540 3110);
PAINT MONO (-540 3110);
FORCEPROP 0 LAST $SEC 1
J 0
(-1425 4950);
DISPLAY 0.680851 (-1425 4950);
PAINT MONO (-1425 4950);
DISPLAY INVISIBLE (-1425 4950);
FORCEPROP 0 LAST CDS_SEC 1
J 0
(-1425 4950);
DISPLAY 1.021277 (-1425 4950);
DISPLAY INVISIBLE (-1425 4950);
FORCEADD Q_CAP..1
(-2125 1950);
FORCEPROP 1 LAST MATERIAL X7R
J 0
(-2075 1850);
DISPLAY 0.510638 (-2075 1850);
PAINT SKYBLUE (-2075 1850);
FORCEPROP 1 LAST PACK_TYPE 0402
J 0
(-2075 1800);
DISPLAY 0.510638 (-2075 1800);
PAINT SKYBLUE (-2075 1800);
FORCEPROP 1 LAST VALUE 0.1UF
J 0
(-2075 2000);
DISPLAY 0.510638 (-2075 2000);
PAINT SKYBLUE (-2075 2000);
FORCEPROP 1 LAST TOLERANCE 10%
J 0
(-2075 1900);
DISPLAY 0.510638 (-2075 1900);
PAINT SKYBLUE (-2075 1900);
FORCEPROP 1 LAST VOLTAGE 25V
J 0
(-2075 1950);
DISPLAY 0.510638 (-2075 1950);
PAINT SKYBLUE (-2075 1950);
FORCEPROP 1 LAST PATH I197
J 0
(-2075 2100);
DISPLAY 0.978723 (-2075 2100);
PAINT WHITE (-2075 2100);
DISPLAY INVISIBLE (-2075 2100);
FORCEPROP 2 LAST SEC_TYPE 0402
J 0
(-2075 2150);
DISPLAY 0.680851 (-2075 2150);
DISPLAY INVISIBLE (-2075 2150);
FORCEPROP 2 LAST CDS_LIB pure_quanta
J 0
(-2125 1950);
DISPLAY INVISIBLE (-2125 1950);
FORCEPROP 1 LAST PART_NUMBER CH4104K1B00
J 0
(-2125 1600);
DISPLAY 0.510638 (-2125 1600);
PAINT WHITE (-2125 1600);
DISPLAY INVISIBLE (-2125 1600);
FORCEPROP 1 LAST LOCATION C225
J 0
(-2075 2050);
DISPLAY 0.702128 (-2075 2050);
PAINT YELLOW (-2075 2050);
FORCEPROP 1 LASTPIN (-2125 2050) $PN 1
J 0
(-2115 2030);
DISPLAY 0.808511 (-2115 2030);
PAINT WHITE (-2115 2030);
FORCEPROP 1 LASTPIN (-2125 1850) $PN 2
J 0
(-2115 1830);
DISPLAY 0.808511 (-2115 1830);
PAINT WHITE (-2115 1830);
FORCEPROP 2 LAST SEC 1
J 0
(-2075 2150);
DISPLAY 0.680851 (-2075 2150);
PAINT MONO (-2075 2150);
DISPLAY INVISIBLE (-2075 2150);
FORCEADD Q_CAP..1
(-2350 1950);
FORCEPROP 1 LAST PACK_TYPE 0402
J 0
(-2300 1800);
DISPLAY 0.510638 (-2300 1800);
PAINT SKYBLUE (-2300 1800);
FORCEPROP 1 LAST VOLTAGE 25V
J 0
(-2300 1950);
DISPLAY 0.510638 (-2300 1950);
PAINT SKYBLUE (-2300 1950);
FORCEPROP 1 LAST TOLERANCE 10%
J 0
(-2300 1900);
DISPLAY 0.510638 (-2300 1900);
PAINT SKYBLUE (-2300 1900);
FORCEPROP 1 LAST MATERIAL X7R
J 0
(-2300 1850);
DISPLAY 0.510638 (-2300 1850);
PAINT SKYBLUE (-2300 1850);
FORCEPROP 1 LAST VALUE 0.1UF
J 0
(-2300 2000);
DISPLAY 0.510638 (-2300 2000);
PAINT SKYBLUE (-2300 2000);
FORCEPROP 1 LAST PATH I198
J 0
(-2300 2100);
DISPLAY 0.978723 (-2300 2100);
PAINT WHITE (-2300 2100);
DISPLAY INVISIBLE (-2300 2100);
FORCEPROP 2 LAST SEC_TYPE 0402
J 0
(-2300 2150);
DISPLAY 0.680851 (-2300 2150);
DISPLAY INVISIBLE (-2300 2150);
FORCEPROP 2 LAST CDS_LIB pure_quanta
J 0
(-2350 1950);
DISPLAY INVISIBLE (-2350 1950);
FORCEPROP 1 LAST PART_NUMBER CH4104K1B00
J 0
(-2350 1600);
DISPLAY 0.510638 (-2350 1600);
PAINT WHITE (-2350 1600);
DISPLAY INVISIBLE (-2350 1600);
FORCEPROP 1 LAST LOCATION C222
J 0
(-2300 2050);
DISPLAY 0.702128 (-2300 2050);
PAINT YELLOW (-2300 2050);
FORCEPROP 1 LASTPIN (-2350 2050) $PN 1
J 0
(-2340 2030);
DISPLAY 0.808511 (-2340 2030);
PAINT WHITE (-2340 2030);
FORCEPROP 1 LASTPIN (-2350 1850) $PN 2
J 0
(-2340 1830);
DISPLAY 0.808511 (-2340 1830);
PAINT WHITE (-2340 1830);
FORCEPROP 2 LAST SEC 1
J 0
(-2300 2150);
DISPLAY 0.680851 (-2300 2150);
PAINT MONO (-2300 2150);
DISPLAY INVISIBLE (-2300 2150);
FORCEADD Q_CAP..1
(-2550 1950);
FORCEPROP 1 LAST PACK_TYPE 0402
J 0
(-2500 1800);
DISPLAY 0.510638 (-2500 1800);
PAINT SKYBLUE (-2500 1800);
FORCEPROP 1 LAST MATERIAL X7R
J 0
(-2500 1850);
DISPLAY 0.510638 (-2500 1850);
PAINT SKYBLUE (-2500 1850);
FORCEPROP 1 LAST TOLERANCE 10%
J 0
(-2500 1900);
DISPLAY 0.510638 (-2500 1900);
PAINT SKYBLUE (-2500 1900);
FORCEPROP 1 LAST VOLTAGE 25V
J 0
(-2500 1950);
DISPLAY 0.510638 (-2500 1950);
PAINT SKYBLUE (-2500 1950);
FORCEPROP 1 LAST VALUE 0.1UF
J 0
(-2500 2000);
DISPLAY 0.510638 (-2500 2000);
PAINT SKYBLUE (-2500 2000);
FORCEPROP 1 LAST PATH I199
J 0
(-2500 2100);
DISPLAY 0.978723 (-2500 2100);
PAINT WHITE (-2500 2100);
DISPLAY INVISIBLE (-2500 2100);
FORCEPROP 2 LAST SEC_TYPE 0402
J 0
(-2500 2150);
DISPLAY 0.680851 (-2500 2150);
DISPLAY INVISIBLE (-2500 2150);
FORCEPROP 2 LAST CDS_LIB pure_quanta
J 0
(-2550 1950);
DISPLAY INVISIBLE (-2550 1950);
FORCEPROP 1 LAST PART_NUMBER CH4104K1B00
J 0
(-2550 1600);
DISPLAY 0.510638 (-2550 1600);
PAINT WHITE (-2550 1600);
DISPLAY INVISIBLE (-2550 1600);
FORCEPROP 1 LAST LOCATION C221
J 0
(-2500 2050);
DISPLAY 0.702128 (-2500 2050);
PAINT YELLOW (-2500 2050);
FORCEPROP 1 LASTPIN (-2550 2050) $PN 1
J 0
(-2540 2030);
DISPLAY 0.808511 (-2540 2030);
PAINT WHITE (-2540 2030);
FORCEPROP 1 LASTPIN (-2550 1850) $PN 2
J 0
(-2540 1830);
DISPLAY 0.808511 (-2540 1830);
PAINT WHITE (-2540 1830);
FORCEPROP 2 LAST SEC 1
J 0
(-2500 2150);
DISPLAY 0.680851 (-2500 2150);
PAINT MONO (-2500 2150);
DISPLAY INVISIBLE (-2500 2150);
FORCEADD OFFPAGE..3
R 2
(-3250 -450);
FORCEPROP 2 LAST $XR0 20 
J 0
(-3499 -450);
DISPLAY 0.638298 (-3499 -450);
PAINT MONO (-3499 -450);
FORCEPROP 2 LAST PATH I2
J 0
(-3475 -400);
DISPLAY 1.021277 (-3475 -400);
DISPLAY INVISIBLE (-3475 -400);
FORCEPROP 1 LAST COMMENT_BODY TRUE
J 2
(-3200 -550);
DISPLAY 0.872340 (-3200 -550);
PAINT PEACH (-3200 -550);
DISPLAY INVISIBLE (-3200 -550);
FORCEPROP 1 LAST OFFPAGE TRUE
J 2
(-3575 -575);
DISPLAY 0.872340 (-3575 -575);
PAINT GREEN (-3575 -575);
DISPLAY INVISIBLE (-3575 -575);
FORCEPROP 2 LAST CDS_LIB standard
J 0
(-3250 -450);
DISPLAY INVISIBLE (-3250 -450);
FORCEADD UNIVERSAL_GND..1
(-2925 950);
FORCEPROP 3 LASTPIN (-2925 1000) SIG_NAME GND\g
J 0
(-2915 1010);
DISPLAY 0.659574 (-2915 1010);
PAINT MONO (-2915 1010);
DISPLAY INVISIBLE (-2915 1010);
FORCEPROP 1 LAST PATH I20
J 0
(-2850 950);
DISPLAY 0.872340 (-2850 950);
PAINT AQUA (-2850 950);
DISPLAY INVISIBLE (-2850 950);
FORCEPROP 1 LAST HDL_POWER GND
J 1
(-2900 875);
DISPLAY 0.702128 (-2900 875);
PAINT GREEN (-2900 875);
DISPLAY INVISIBLE (-2900 875);
FORCEPROP 2 LAST CDS_LIB logical_power
J 0
(-2925 950);
DISPLAY INVISIBLE (-2925 950);
FORCEADD UNIVERSAL_GND..1
(-2550 1700);
FORCEPROP 3 LASTPIN (-2550 1750) SIG_NAME GND\g
J 0
(-2540 1760);
DISPLAY 0.659574 (-2540 1760);
PAINT MONO (-2540 1760);
DISPLAY INVISIBLE (-2540 1760);
FORCEPROP 1 LAST PATH I200
J 0
(-2475 1700);
DISPLAY 0.872340 (-2475 1700);
PAINT AQUA (-2475 1700);
DISPLAY INVISIBLE (-2475 1700);
FORCEPROP 1 LAST HDL_POWER GND
J 1
(-2525 1625);
DISPLAY 0.702128 (-2525 1625);
PAINT GREEN (-2525 1625);
DISPLAY INVISIBLE (-2525 1625);
FORCEPROP 2 LAST CDS_LIB logical_power
J 0
(-2550 1700);
DISPLAY INVISIBLE (-2550 1700);
FORCEADD Q_CAP..1
(-2775 1300);
FORCEPROP 1 LAST PACK_TYPE 0402
J 0
(-2725 1150);
DISPLAY 0.510638 (-2725 1150);
PAINT SKYBLUE (-2725 1150);
FORCEPROP 1 LAST VOLTAGE 25V
J 0
(-2725 1300);
DISPLAY 0.510638 (-2725 1300);
PAINT SKYBLUE (-2725 1300);
FORCEPROP 1 LAST TOLERANCE 10%
J 0
(-2725 1250);
DISPLAY 0.510638 (-2725 1250);
PAINT SKYBLUE (-2725 1250);
FORCEPROP 1 LAST PART_NUMBER CH4104K1B00
J 0
(-2725 1100);
DISPLAY 0.510638 (-2725 1100);
PAINT WHITE (-2725 1100);
FORCEPROP 1 LAST MATERIAL X7R
J 0
(-2725 1200);
DISPLAY 0.510638 (-2725 1200);
PAINT SKYBLUE (-2725 1200);
FORCEPROP 1 LAST VALUE 0.1UF
J 0
(-2725 1350);
DISPLAY 0.510638 (-2725 1350);
PAINT SKYBLUE (-2725 1350);
FORCEPROP 1 LAST PATH I21
J 0
(-2725 1450);
DISPLAY 0.978723 (-2725 1450);
PAINT WHITE (-2725 1450);
DISPLAY INVISIBLE (-2725 1450);
FORCEPROP 2 LAST CDS_LIB pure_quanta
J 0
(-2775 1300);
DISPLAY INVISIBLE (-2775 1300);
FORCEPROP 2 LAST SEC_TYPE 0402
J 0
(-2725 1500);
DISPLAY 0.680851 (-2725 1500);
DISPLAY INVISIBLE (-2725 1500);
FORCEPROP 1 LAST LOCATION C8
J 0
(-2725 1400);
DISPLAY 0.702128 (-2725 1400);
PAINT YELLOW (-2725 1400);
FORCEPROP 1 LASTPIN (-2775 1400) $PN 1
J 0
(-2765 1380);
DISPLAY 0.808511 (-2765 1380);
PAINT WHITE (-2765 1380);
FORCEPROP 1 LASTPIN (-2775 1200) $PN 2
J 0
(-2765 1180);
DISPLAY 0.808511 (-2765 1180);
PAINT WHITE (-2765 1180);
FORCEPROP 2 LAST SEC 1
J 0
(-2725 1500);
DISPLAY 0.680851 (-2725 1500);
PAINT MONO (-2725 1500);
DISPLAY INVISIBLE (-2725 1500);
FORCEADD UNIVERSAL_POWER..1
(-3050 1625);
FORCEPROP 3 LASTPIN (-3050 1575) SIG_NAME P2V5_AUX\g
J 0
(-3040 1585);
DISPLAY 0.659574 (-3040 1585);
PAINT MONO (-3040 1585);
DISPLAY INVISIBLE (-3040 1585);
FORCEPROP 1 LAST HDL_POWER P2V5_AUX
J 1
(-3050 1675);
DISPLAY 0.702128 (-3050 1675);
PAINT GREEN (-3050 1675);
FORCEPROP 1 LAST PATH I22
J 0
(-3000 1650);
DISPLAY 0.872340 (-3000 1650);
PAINT AQUA (-3000 1650);
DISPLAY INVISIBLE (-3000 1650);
FORCEPROP 2 LAST CDS_LIB logical_power
J 0
(-3050 1625);
DISPLAY INVISIBLE (-3050 1625);
FORCEADD Q_CAP..1
(-2875 2475);
FORCEPROP 1 LAST VOLTAGE 25V
J 0
(-2825 2475);
DISPLAY 0.510638 (-2825 2475);
PAINT SKYBLUE (-2825 2475);
FORCEPROP 1 LAST TOLERANCE 10%
J 0
(-2825 2425);
DISPLAY 0.510638 (-2825 2425);
PAINT SKYBLUE (-2825 2425);
FORCEPROP 1 LAST VALUE 1UF
J 0
(-2825 2525);
DISPLAY 0.510638 (-2825 2525);
PAINT SKYBLUE (-2825 2525);
FORCEPROP 1 LAST MATERIAL X6S
J 0
(-2825 2375);
DISPLAY 0.510638 (-2825 2375);
PAINT SKYBLUE (-2825 2375);
FORCEPROP 1 LAST PACK_TYPE C0402
J 0
(-2850 2325);
DISPLAY 0.510638 (-2850 2325);
PAINT SKYBLUE (-2850 2325);
FORCEPROP 1 LAST PATH I23
J 0
(-2825 2625);
DISPLAY 0.978723 (-2825 2625);
PAINT WHITE (-2825 2625);
DISPLAY INVISIBLE (-2825 2625);
FORCEPROP 2 LAST CDS_LIB pure_quanta
J 0
(-2875 2475);
DISPLAY INVISIBLE (-2875 2475);
FORCEPROP 2 LAST SEC_TYPE C0402
J 0
(-2825 2675);
DISPLAY 0.680851 (-2825 2675);
DISPLAY INVISIBLE (-2825 2675);
FORCEPROP 1 LAST PART_NUMBER CH5104KEB02
J 0
(-2825 2325);
DISPLAY 0.510638 (-2825 2325);
PAINT WHITE (-2825 2325);
DISPLAY INVISIBLE (-2825 2325);
FORCEPROP 1 LAST LOCATION C5
J 0
(-2825 2575);
DISPLAY 0.702128 (-2825 2575);
PAINT YELLOW (-2825 2575);
FORCEPROP 1 LASTPIN (-2875 2575) $PN 1
J 0
(-2865 2555);
DISPLAY 0.808511 (-2865 2555);
PAINT WHITE (-2865 2555);
FORCEPROP 1 LASTPIN (-2875 2375) $PN 2
J 0
(-2865 2355);
DISPLAY 0.808511 (-2865 2355);
PAINT WHITE (-2865 2355);
FORCEPROP 2 LAST SEC 1
J 0
(-2825 2675);
DISPLAY 0.680851 (-2825 2675);
PAINT MONO (-2825 2675);
DISPLAY INVISIBLE (-2825 2675);
FORCEADD Q_CAP..1
(-2650 2475);
FORCEPROP 1 LAST PACK_TYPE 0402
J 0
(-2600 2325);
DISPLAY 0.510638 (-2600 2325);
PAINT SKYBLUE (-2600 2325);
FORCEPROP 1 LAST VOLTAGE 25V
J 0
(-2600 2475);
DISPLAY 0.510638 (-2600 2475);
PAINT SKYBLUE (-2600 2475);
FORCEPROP 1 LAST TOLERANCE 10%
J 0
(-2600 2425);
DISPLAY 0.510638 (-2600 2425);
PAINT SKYBLUE (-2600 2425);
FORCEPROP 1 LAST VALUE 0.1UF
J 0
(-2600 2525);
DISPLAY 0.510638 (-2600 2525);
PAINT SKYBLUE (-2600 2525);
FORCEPROP 1 LAST MATERIAL X7R
J 0
(-2600 2375);
DISPLAY 0.510638 (-2600 2375);
PAINT SKYBLUE (-2600 2375);
FORCEPROP 1 LAST PART_NUMBER CH4104K1B00
J 0
(-2700 2150);
DISPLAY 0.510638 (-2700 2150);
PAINT WHITE (-2700 2150);
FORCEPROP 1 LAST PATH I24
J 0
(-2600 2625);
DISPLAY 0.978723 (-2600 2625);
PAINT WHITE (-2600 2625);
DISPLAY INVISIBLE (-2600 2625);
FORCEPROP 2 LAST CDS_LIB pure_quanta
J 0
(-2650 2475);
DISPLAY INVISIBLE (-2650 2475);
FORCEPROP 2 LAST SEC_TYPE 0402
J 0
(-2600 2675);
DISPLAY 0.680851 (-2600 2675);
DISPLAY INVISIBLE (-2600 2675);
FORCEPROP 1 LAST LOCATION C7
J 0
(-2600 2575);
DISPLAY 0.702128 (-2600 2575);
PAINT YELLOW (-2600 2575);
FORCEPROP 1 LASTPIN (-2650 2575) $PN 1
J 0
(-2640 2555);
DISPLAY 0.808511 (-2640 2555);
PAINT WHITE (-2640 2555);
FORCEPROP 1 LASTPIN (-2650 2375) $PN 2
J 0
(-2640 2355);
DISPLAY 0.808511 (-2640 2355);
PAINT WHITE (-2640 2355);
FORCEPROP 2 LAST SEC 1
J 0
(-2600 2675);
DISPLAY 0.680851 (-2600 2675);
PAINT MONO (-2600 2675);
DISPLAY INVISIBLE (-2600 2675);
FORCEADD Q_CAP..1
(-2400 2475);
FORCEPROP 1 LAST PART_NUMBER CH11006JB00
J 0
(-2350 2275);
DISPLAY 0.510638 (-2350 2275);
PAINT WHITE (-2350 2275);
FORCEPROP 1 LAST PACK_TYPE 0402
J 0
(-2350 2325);
DISPLAY 0.510638 (-2350 2325);
PAINT SKYBLUE (-2350 2325);
FORCEPROP 1 LAST MATERIAL NPO
J 0
(-2350 2375);
DISPLAY 0.510638 (-2350 2375);
PAINT SKYBLUE (-2350 2375);
FORCEPROP 1 LAST TOLERANCE 5%
J 0
(-2350 2425);
DISPLAY 0.510638 (-2350 2425);
PAINT SKYBLUE (-2350 2425);
FORCEPROP 1 LAST VOLTAGE 50V
J 0
(-2350 2475);
DISPLAY 0.510638 (-2350 2475);
PAINT SKYBLUE (-2350 2475);
FORCEPROP 1 LAST VALUE 100PF
J 0
(-2350 2525);
DISPLAY 0.510638 (-2350 2525);
PAINT SKYBLUE (-2350 2525);
FORCEPROP 1 LAST PATH I25
J 0
(-2350 2625);
DISPLAY 0.978723 (-2350 2625);
PAINT WHITE (-2350 2625);
DISPLAY INVISIBLE (-2350 2625);
FORCEPROP 2 LAST CDS_LIB pure_quanta
J 0
(-2400 2475);
DISPLAY INVISIBLE (-2400 2475);
FORCEPROP 2 LAST SEC_TYPE 0402
J 0
(-2350 2675);
DISPLAY 0.680851 (-2350 2675);
DISPLAY INVISIBLE (-2350 2675);
FORCEPROP 1 LAST LOCATION C9
J 0
(-2350 2575);
DISPLAY 0.702128 (-2350 2575);
PAINT YELLOW (-2350 2575);
FORCEPROP 1 LASTPIN (-2400 2575) $PN 1
J 0
(-2390 2555);
DISPLAY 0.808511 (-2390 2555);
PAINT WHITE (-2390 2555);
FORCEPROP 1 LASTPIN (-2400 2375) $PN 2
J 0
(-2390 2355);
DISPLAY 0.808511 (-2390 2355);
PAINT WHITE (-2390 2355);
FORCEPROP 2 LAST SEC 1
J 0
(-2350 2675);
DISPLAY 0.680851 (-2350 2675);
PAINT MONO (-2350 2675);
DISPLAY INVISIBLE (-2350 2675);
FORCEADD Q_RES..2
(-250 -75);
FORCEPROP 1 LAST WATTAGE 1/16W
J 0
(-210 -100);
DISPLAY 0.510638 (-210 -100);
PAINT SKYBLUE (-210 -100);
FORCEPROP 1 LAST TOLERANCE 1%
J 0
(-205 -50);
DISPLAY 0.510638 (-205 -50);
PAINT SKYBLUE (-205 -50);
FORCEPROP 1 LAST VALUE 1K
J 0
(-205 0);
DISPLAY 0.510638 (-205 0);
PAINT SKYBLUE (-205 0);
FORCEPROP 1 LAST MATERIAL CHIP
J 0
(-210 -150);
DISPLAY 0.510638 (-210 -150);
PAINT SKYBLUE (-210 -150);
FORCEPROP 1 LAST PART_NUMBER CS21002FB06
J 0
(-210 -200);
DISPLAY 0.510638 (-210 -200);
PAINT WHITE (-210 -200);
FORCEPROP 1 LAST PACK_TYPE 0402LF
J 0
(-210 -250);
DISPLAY 0.510638 (-210 -250);
PAINT SKYBLUE (-210 -250);
FORCEPROP 1 LAST PATH I27
J 0
(-200 100);
DISPLAY 0.978723 (-200 100);
PAINT WHITE (-200 100);
DISPLAY INVISIBLE (-200 100);
FORCEPROP 2 LAST CDS_LIB pure_quanta
J 0
(-250 -75);
DISPLAY INVISIBLE (-250 -75);
FORCEPROP 1 LAST LOCATION R325
J 0
(-205 50);
DISPLAY 0.702128 (-205 50);
PAINT YELLOW (-205 50);
FORCEPROP 0 LAST $SEC 1
J 0
(-200 100);
DISPLAY 0.680851 (-200 100);
PAINT MONO (-200 100);
DISPLAY INVISIBLE (-200 100);
FORCEPROP 0 LAST CDS_SEC 1
J 0
(-200 100);
DISPLAY 0.680851 (-200 100);
DISPLAY INVISIBLE (-200 100);
FORCEPROP 1 LASTPIN (-250 25) $PN 1
J 0
(-245 -13);
DISPLAY 0.808511 (-245 -13);
PAINT WHITE (-245 -13);
DISPLAY INVISIBLE (-245 -13);
FORCEPROP 1 LASTPIN (-250 -175) $PN 2
J 0
(-245 -165);
DISPLAY 0.808511 (-245 -165);
PAINT WHITE (-245 -165);
DISPLAY INVISIBLE (-245 -165);
FORCEADD Q_RES..2
(-250 350);
FORCEPROP 1 LAST PACK_TYPE 0402LF
J 0
(-210 175);
DISPLAY 0.510638 (-210 175);
PAINT SKYBLUE (-210 175);
FORCEPROP 1 LAST MATERIAL CHIP
J 0
(-210 275);
DISPLAY 0.510638 (-210 275);
PAINT SKYBLUE (-210 275);
FORCEPROP 1 LAST WATTAGE 1/16W
J 0
(-210 325);
DISPLAY 0.510638 (-210 325);
PAINT SKYBLUE (-210 325);
FORCEPROP 1 LAST VALUE 1K
J 0
(-205 425);
DISPLAY 0.510638 (-205 425);
PAINT SKYBLUE (-205 425);
FORCEPROP 1 LAST PART_NUMBER CS21002FB06
J 0
(-210 225);
DISPLAY 0.510638 (-210 225);
PAINT WHITE (-210 225);
FORCEPROP 1 LAST TOLERANCE 1%
J 0
(-205 375);
DISPLAY 0.510638 (-205 375);
PAINT SKYBLUE (-205 375);
FORCEPROP 1 LAST PATH I28
J 0
(-200 525);
DISPLAY 0.978723 (-200 525);
PAINT WHITE (-200 525);
DISPLAY INVISIBLE (-200 525);
FORCEPROP 2 LAST CDS_LIB pure_quanta
J 0
(-250 350);
DISPLAY INVISIBLE (-250 350);
FORCEPROP 1 LAST LOCATION R324
J 0
(-205 475);
DISPLAY 0.702128 (-205 475);
PAINT YELLOW (-205 475);
FORCEPROP 0 LAST $SEC 1
J 0
(-200 525);
DISPLAY 0.680851 (-200 525);
PAINT MONO (-200 525);
DISPLAY INVISIBLE (-200 525);
FORCEPROP 0 LAST CDS_SEC 1
J 0
(-200 525);
DISPLAY 0.680851 (-200 525);
DISPLAY INVISIBLE (-200 525);
FORCEPROP 1 LASTPIN (-250 450) $PN 1
J 0
(-245 412);
DISPLAY 0.808511 (-245 412);
PAINT WHITE (-245 412);
DISPLAY INVISIBLE (-245 412);
FORCEPROP 1 LASTPIN (-250 250) $PN 2
J 0
(-245 260);
DISPLAY 0.808511 (-245 260);
PAINT WHITE (-245 260);
DISPLAY INVISIBLE (-245 260);
FORCEADD OFFPAGE..1
(1100 -1150);
FORCEPROP 2 LAST $XR1 20 
J 0
(759 -1150);
DISPLAY 0.638298 (759 -1150);
PAINT MONO (759 -1150);
FORCEPROP 2 LAST $XR0 12 
J 0
(849 -1150);
DISPLAY 0.638298 (849 -1150);
PAINT MONO (849 -1150);
FORCEPROP 2 LAST PATH I29
J 0
(900 -1100);
DISPLAY 1.021277 (900 -1100);
DISPLAY INVISIBLE (900 -1100);
FORCEPROP 1 LAST COMMENT_BODY TRUE
J 0
(1225 -1250);
DISPLAY 0.872340 (1225 -1250);
PAINT PEACH (1225 -1250);
DISPLAY INVISIBLE (1225 -1250);
FORCEPROP 1 LAST OFFPAGE TRUE
J 0
(1425 -1275);
DISPLAY 0.872340 (1425 -1275);
PAINT GREEN (1425 -1275);
DISPLAY INVISIBLE (1425 -1275);
FORCEPROP 2 LAST CDS_LIB standard
J 0
(1100 -1150);
DISPLAY INVISIBLE (1100 -1150);
FORCEADD UNIVERSAL_GND..1
(-3600 2050);
FORCEPROP 3 LASTPIN (-3600 2100) SIG_NAME GND\g
J 0
(-3590 2110);
DISPLAY 0.659574 (-3590 2110);
PAINT MONO (-3590 2110);
DISPLAY INVISIBLE (-3590 2110);
FORCEPROP 1 LAST PATH I3
J 0
(-3525 2050);
DISPLAY 0.872340 (-3525 2050);
PAINT AQUA (-3525 2050);
DISPLAY INVISIBLE (-3525 2050);
FORCEPROP 1 LAST HDL_POWER GND
J 1
(-3575 1975);
DISPLAY 0.702128 (-3575 1975);
PAINT GREEN (-3575 1975);
DISPLAY INVISIBLE (-3575 1975);
FORCEPROP 2 LAST CDS_LIB logical_power
J 0
(-3600 2050);
DISPLAY INVISIBLE (-3600 2050);
FORCEADD OFFPAGE..1
(1100 -950);
FORCEPROP 2 LAST $XR1 20 
J 0
(759 -950);
DISPLAY 0.638298 (759 -950);
PAINT MONO (759 -950);
FORCEPROP 2 LAST $XR0 12 
J 0
(849 -950);
DISPLAY 0.638298 (849 -950);
PAINT MONO (849 -950);
FORCEPROP 2 LAST PATH I30
J 0
(900 -900);
DISPLAY 1.021277 (900 -900);
DISPLAY INVISIBLE (900 -900);
FORCEPROP 1 LAST COMMENT_BODY TRUE
J 0
(1225 -1050);
DISPLAY 0.872340 (1225 -1050);
PAINT PEACH (1225 -1050);
DISPLAY INVISIBLE (1225 -1050);
FORCEPROP 1 LAST OFFPAGE TRUE
J 0
(1425 -1075);
DISPLAY 0.872340 (1425 -1075);
PAINT GREEN (1425 -1075);
DISPLAY INVISIBLE (1425 -1075);
FORCEPROP 2 LAST CDS_LIB standard
J 0
(1100 -950);
DISPLAY INVISIBLE (1100 -950);
FORCEADD UNIVERSAL_GND..1
(350 -475);
FORCEPROP 3 LASTPIN (350 -425) SIG_NAME GND\g
J 0
(360 -415);
DISPLAY 0.659574 (360 -415);
PAINT MONO (360 -415);
DISPLAY INVISIBLE (360 -415);
FORCEPROP 1 LAST PATH I31
J 0
(425 -475);
DISPLAY 0.872340 (425 -475);
PAINT AQUA (425 -475);
DISPLAY INVISIBLE (425 -475);
FORCEPROP 1 LAST HDL_POWER GND
J 1
(375 -550);
DISPLAY 0.702128 (375 -550);
PAINT GREEN (375 -550);
DISPLAY INVISIBLE (375 -550);
FORCEPROP 2 LAST CDS_LIB logical_power
J 0
(350 -475);
DISPLAY INVISIBLE (350 -475);
FORCEADD Q_CAP..1
(150 -75);
FORCEPROP 1 LAST PACK_TYPE 0402
J 0
(200 -275);
DISPLAY 0.510638 (200 -275);
PAINT SKYBLUE (200 -275);
FORCEPROP 1 LAST TOLERANCE 10%
J 0
(200 -125);
DISPLAY 0.510638 (200 -125);
PAINT SKYBLUE (200 -125);
FORCEPROP 1 LAST MATERIAL X7R
J 0
(200 -175);
DISPLAY 0.510638 (200 -175);
PAINT SKYBLUE (200 -175);
FORCEPROP 1 LAST VOLTAGE 25V
J 0
(200 -75);
DISPLAY 0.510638 (200 -75);
PAINT SKYBLUE (200 -75);
FORCEPROP 1 LAST PART_NUMBER CH4104K1B00
J 0
(200 -225);
DISPLAY 0.510638 (200 -225);
PAINT WHITE (200 -225);
FORCEPROP 1 LAST VALUE 0.1UF
J 0
(200 -25);
DISPLAY 0.510638 (200 -25);
PAINT SKYBLUE (200 -25);
FORCEPROP 1 LAST PATH I32
J 0
(200 75);
DISPLAY 0.978723 (200 75);
PAINT WHITE (200 75);
DISPLAY INVISIBLE (200 75);
FORCEPROP 2 LAST CDS_LIB pure_quanta
J 0
(150 -75);
DISPLAY INVISIBLE (150 -75);
FORCEPROP 1 LAST LOCATION C168
J 0
(200 25);
DISPLAY 0.702128 (200 25);
PAINT YELLOW (200 25);
FORCEPROP 1 LASTPIN (150 25) $PN 1
J 0
(160 5);
DISPLAY 0.808511 (160 5);
PAINT WHITE (160 5);
FORCEPROP 1 LASTPIN (150 -175) $PN 2
J 0
(160 -195);
DISPLAY 0.808511 (160 -195);
PAINT WHITE (160 -195);
FORCEPROP 0 LAST $SEC 1
J 0
(200 75);
DISPLAY 0.680851 (200 75);
PAINT MONO (200 75);
DISPLAY INVISIBLE (200 75);
FORCEPROP 0 LAST CDS_SEC 1
J 0
(200 75);
DISPLAY 0.680851 (200 75);
DISPLAY INVISIBLE (200 75);
FORCEADD Q_CAP..1
(550 -75);
FORCEPROP 1 LAST VOLTAGE 50V
J 0
(600 -75);
DISPLAY 0.510638 (600 -75);
PAINT SKYBLUE (600 -75);
FORCEPROP 1 LAST PACK_TYPE C0402
J 0
(600 -275);
DISPLAY 0.510638 (600 -275);
PAINT SKYBLUE (600 -275);
FORCEPROP 1 LAST TOLERANCE 10%
J 0
(600 -125);
DISPLAY 0.510638 (600 -125);
PAINT SKYBLUE (600 -125);
FORCEPROP 1 LAST MATERIAL X7R
J 0
(600 -175);
DISPLAY 0.510638 (600 -175);
PAINT SKYBLUE (600 -175);
FORCEPROP 1 LAST PART_NUMBER CH31006KB18
J 0
(600 -225);
DISPLAY 0.510638 (600 -225);
PAINT WHITE (600 -225);
FORCEPROP 1 LAST VALUE 0.01UF
J 0
(600 -25);
DISPLAY 0.510638 (600 -25);
PAINT SKYBLUE (600 -25);
FORCEPROP 1 LAST PATH I33
J 0
(600 75);
DISPLAY 0.978723 (600 75);
PAINT WHITE (600 75);
DISPLAY INVISIBLE (600 75);
FORCEPROP 2 LAST CDS_LIB pure_quanta
J 0
(550 -75);
DISPLAY INVISIBLE (550 -75);
FORCEPROP 1 LAST LOCATION C170
J 0
(600 25);
DISPLAY 0.702128 (600 25);
PAINT YELLOW (600 25);
FORCEPROP 1 LASTPIN (550 25) $PN 1
J 0
(560 5);
DISPLAY 0.808511 (560 5);
PAINT WHITE (560 5);
FORCEPROP 1 LASTPIN (550 -175) $PN 2
J 0
(560 -195);
DISPLAY 0.808511 (560 -195);
PAINT WHITE (560 -195);
FORCEPROP 0 LAST $SEC 1
J 0
(600 75);
DISPLAY 0.680851 (600 75);
PAINT MONO (600 75);
DISPLAY INVISIBLE (600 75);
FORCEPROP 0 LAST CDS_SEC 1
J 0
(600 75);
DISPLAY 0.680851 (600 75);
DISPLAY INVISIBLE (600 75);
FORCEADD Q_CAP..1
(475 400);
FORCEPROP 1 LAST MATERIAL EMPTY
J 0
(525 300);
DISPLAY 0.510638 (525 300);
PAINT RED (525 300);
FORCEPROP 1 LAST PACK_TYPE C0402
J 0
(525 200);
DISPLAY 0.510638 (525 200);
PAINT SKYBLUE (525 200);
FORCEPROP 1 LAST PART_NUMBER CH31006KB18
J 0
(525 250);
DISPLAY 0.510638 (525 250);
PAINT WHITE (525 250);
FORCEPROP 1 LAST VALUE 0.01UF
J 0
(525 450);
DISPLAY 0.510638 (525 450);
PAINT SKYBLUE (525 450);
FORCEPROP 1 LAST VOLTAGE 50V
J 0
(525 400);
DISPLAY 0.510638 (525 400);
PAINT SKYBLUE (525 400);
FORCEPROP 1 LAST TOLERANCE 10%
J 0
(525 350);
DISPLAY 0.510638 (525 350);
PAINT SKYBLUE (525 350);
FORCEPROP 1 LAST PATH I34
J 0
(525 550);
DISPLAY 0.978723 (525 550);
PAINT WHITE (525 550);
DISPLAY INVISIBLE (525 550);
FORCEPROP 2 LAST CDS_LIB pure_quanta
J 0
(475 400);
DISPLAY INVISIBLE (475 400);
FORCEPROP 1 LAST LOCATION C169
J 0
(525 500);
DISPLAY 0.702128 (525 500);
PAINT YELLOW (525 500);
FORCEPROP 1 LASTPIN (475 500) $PN 1
J 0
(485 480);
DISPLAY 0.808511 (485 480);
PAINT WHITE (485 480);
FORCEPROP 1 LASTPIN (475 300) $PN 2
J 0
(485 280);
DISPLAY 0.808511 (485 280);
PAINT WHITE (485 280);
FORCEPROP 0 LAST $SEC 1
J 0
(525 550);
DISPLAY 0.680851 (525 550);
PAINT MONO (525 550);
DISPLAY INVISIBLE (525 550);
FORCEPROP 0 LAST CDS_SEC 1
J 0
(525 550);
DISPLAY 0.680851 (525 550);
DISPLAY INVISIBLE (525 550);
FORCEADD UNIVERSAL_POWER..1
(-250 775);
FORCEPROP 3 LASTPIN (-250 725) SIG_NAME P1V2_AUX\g
J 0
(-240 735);
DISPLAY 0.659574 (-240 735);
PAINT MONO (-240 735);
DISPLAY INVISIBLE (-240 735);
FORCEPROP 1 LAST HDL_POWER P1V2_AUX
J 1
(-250 825);
DISPLAY 0.702128 (-250 825);
PAINT GREEN (-250 825);
FORCEPROP 1 LAST PATH I35
J 0
(-200 800);
DISPLAY 0.872340 (-200 800);
PAINT AQUA (-200 800);
DISPLAY INVISIBLE (-200 800);
FORCEPROP 2 LAST CDS_LIB logical_power
J 0
(-250 775);
DISPLAY INVISIBLE (-250 775);
FORCEADD UNIVERSAL_GND..1
(-275 1325);
FORCEPROP 3 LASTPIN (-275 1375) SIG_NAME GND\g
J 0
(-265 1385);
DISPLAY 0.659574 (-265 1385);
PAINT MONO (-265 1385);
DISPLAY INVISIBLE (-265 1385);
FORCEPROP 1 LAST PATH I36
J 0
(-200 1325);
DISPLAY 0.872340 (-200 1325);
PAINT AQUA (-200 1325);
DISPLAY INVISIBLE (-200 1325);
FORCEPROP 1 LAST HDL_POWER GND
J 1
(-250 1250);
DISPLAY 0.702128 (-250 1250);
PAINT GREEN (-250 1250);
DISPLAY INVISIBLE (-250 1250);
FORCEPROP 2 LAST CDS_LIB logical_power
J 0
(-275 1325);
DISPLAY INVISIBLE (-275 1325);
FORCEADD OFFPAGE..4
(450 2300);
FORCEPROP 2 LAST $XR0 20 
J 0
(636 2300);
DISPLAY 0.638298 (636 2300);
PAINT MONO (636 2300);
FORCEPROP 2 LAST PATH I37
J 0
(650 2350);
DISPLAY 1.021277 (650 2350);
DISPLAY INVISIBLE (650 2350);
FORCEPROP 1 LAST COMMENT_BODY TRUE
J 0
(425 2200);
DISPLAY 1.574468 (425 2200);
PAINT PEACH (425 2200);
DISPLAY INVISIBLE (425 2200);
FORCEPROP 1 LAST OFFPAGE TRUE
J 0
(775 2175);
DISPLAY 1.574468 (775 2175);
PAINT GREEN (775 2175);
DISPLAY INVISIBLE (775 2175);
FORCEPROP 2 LAST CDS_LIB standard
J 0
(450 2300);
DISPLAY INVISIBLE (450 2300);
FORCEADD OFFPAGE..3
(450 2500);
FORCEPROP 2 LAST $XR0 20 
J 0
(664 2500);
DISPLAY 0.638298 (664 2500);
PAINT MONO (664 2500);
FORCEPROP 2 LAST PATH I38
J 0
(675 2550);
DISPLAY 1.021277 (675 2550);
DISPLAY INVISIBLE (675 2550);
FORCEPROP 1 LAST COMMENT_BODY TRUE
J 0
(400 2400);
DISPLAY 0.872340 (400 2400);
PAINT PEACH (400 2400);
DISPLAY INVISIBLE (400 2400);
FORCEPROP 1 LAST OFFPAGE TRUE
J 0
(775 2375);
DISPLAY 0.872340 (775 2375);
PAINT GREEN (775 2375);
DISPLAY INVISIBLE (775 2375);
FORCEPROP 2 LAST CDS_LIB standard
J 0
(450 2500);
DISPLAY INVISIBLE (450 2500);
FORCEADD UNIVERSAL_GND..1
(800 2450);
FORCEPROP 3 LASTPIN (800 2500) SIG_NAME GND\g
J 0
(810 2510);
DISPLAY 0.659574 (810 2510);
PAINT MONO (810 2510);
DISPLAY INVISIBLE (810 2510);
FORCEPROP 1 LAST PATH I39
J 0
(875 2450);
DISPLAY 0.872340 (875 2450);
PAINT AQUA (875 2450);
DISPLAY INVISIBLE (875 2450);
FORCEPROP 1 LAST HDL_POWER GND
J 1
(825 2375);
DISPLAY 0.702128 (825 2375);
PAINT GREEN (825 2375);
DISPLAY INVISIBLE (825 2375);
FORCEPROP 2 LAST CDS_LIB logical_power
J 0
(800 2450);
DISPLAY INVISIBLE (800 2450);
FORCEADD Q_CAP..1
(-3700 2475);
FORCEPROP 1 LAST MATERIAL X6S
J 0
(-3650 2375);
DISPLAY 0.510638 (-3650 2375);
PAINT SKYBLUE (-3650 2375);
FORCEPROP 1 LAST TOLERANCE 10%
J 0
(-3650 2425);
DISPLAY 0.510638 (-3650 2425);
PAINT SKYBLUE (-3650 2425);
FORCEPROP 1 LAST VOLTAGE 25V
J 0
(-3650 2475);
DISPLAY 0.510638 (-3650 2475);
PAINT SKYBLUE (-3650 2475);
FORCEPROP 1 LAST VALUE 4.7UF
J 0
(-3650 2525);
DISPLAY 0.510638 (-3650 2525);
PAINT SKYBLUE (-3650 2525);
FORCEPROP 1 LAST PART_NUMBER CH5474KE906
R 3
J 0
(-3750 2425);
DISPLAY 0.510638 (-3750 2425);
PAINT WHITE (-3750 2425);
FORCEPROP 1 LAST PACK_TYPE C0603
J 0
(-3650 2325);
DISPLAY 0.510638 (-3650 2325);
PAINT SKYBLUE (-3650 2325);
FORCEPROP 1 LAST PATH I4
J 0
(-3650 2625);
DISPLAY 0.978723 (-3650 2625);
PAINT WHITE (-3650 2625);
DISPLAY INVISIBLE (-3650 2625);
FORCEPROP 2 LAST SEC_TYPE C0603
J 0
(-3650 2675);
DISPLAY 0.680851 (-3650 2675);
DISPLAY INVISIBLE (-3650 2675);
FORCEPROP 2 LAST CDS_LIB pure_quanta
J 0
(-3700 2475);
DISPLAY INVISIBLE (-3700 2475);
FORCEPROP 1 LAST LOCATION C1
J 0
(-3650 2575);
DISPLAY 0.702128 (-3650 2575);
PAINT YELLOW (-3650 2575);
FORCEPROP 1 LASTPIN (-3700 2575) $PN 1
J 0
(-3690 2555);
DISPLAY 0.808511 (-3690 2555);
PAINT WHITE (-3690 2555);
FORCEPROP 1 LASTPIN (-3700 2375) $PN 2
J 0
(-3690 2355);
DISPLAY 0.808511 (-3690 2355);
PAINT WHITE (-3690 2355);
FORCEPROP 2 LAST SEC 1
J 0
(-3650 2675);
DISPLAY 0.680851 (-3650 2675);
PAINT MONO (-3650 2675);
DISPLAY INVISIBLE (-3650 2675);
FORCEADD OFFPAGE..1
(-2550 2900);
FORCEPROP 2 LAST $XR0 12 
J 0
(-2771 2900);
DISPLAY 0.638298 (-2771 2900);
PAINT MONO (-2771 2900);
FORCEPROP 2 LAST PATH I40
J 0
(-2725 2950);
DISPLAY 1.021277 (-2725 2950);
DISPLAY INVISIBLE (-2725 2950);
FORCEPROP 1 LAST COMMENT_BODY TRUE
J 0
(-2425 2800);
DISPLAY 0.872340 (-2425 2800);
PAINT PEACH (-2425 2800);
DISPLAY INVISIBLE (-2425 2800);
FORCEPROP 1 LAST OFFPAGE TRUE
J 0
(-2225 2775);
DISPLAY 0.872340 (-2225 2775);
PAINT GREEN (-2225 2775);
DISPLAY INVISIBLE (-2225 2775);
FORCEPROP 2 LAST CDS_LIB standard
J 0
(-2550 2900);
DISPLAY INVISIBLE (-2550 2900);
FORCEADD TAP..1
R 2
(-2025 3200);
FORCEPROP 3 LASTPIN (-1975 3200) SIG_NAME M_BMC_DDR4_MA<11>
J 0
(-1965 3210);
DISPLAY 0.659574 (-1965 3210);
PAINT MONO (-1965 3210);
DISPLAY INVISIBLE (-1965 3210);
FORCEPROP 1 LASTPIN (-1975 3200) BN 11
J 2
(-1963 3208);
DISPLAY 0.680851 (-1963 3208);
PAINT MONO (-1963 3208);
FORCEPROP 1 LAST PATH I41
J 2
(-2023 3200);
DISPLAY 0.872340 (-2023 3200);
PAINT GREEN (-2023 3200);
DISPLAY INVISIBLE (-2023 3200);
FORCEPROP 1 LAST HDL_TAP TRUE
J 2
(-2350 3075);
DISPLAY 0.872340 (-2350 3075);
DISPLAY INVISIBLE (-2350 3075);
FORCEPROP 1 LAST BODY_TYPE PLUMBING
J 2
(-2025 3250);
DISPLAY 0.872340 (-2025 3250);
PAINT GREEN (-2025 3250);
DISPLAY INVISIBLE (-2025 3250);
FORCEPROP 2 LAST CDS_LIB standard
J 0
(-2025 3200);
DISPLAY INVISIBLE (-2025 3200);
FORCEADD TAP..1
R 2
(-2025 3150);
FORCEPROP 3 LASTPIN (-1975 3150) SIG_NAME M_BMC_DDR4_MA<12>
J 0
(-1965 3160);
DISPLAY 0.659574 (-1965 3160);
PAINT MONO (-1965 3160);
DISPLAY INVISIBLE (-1965 3160);
FORCEPROP 1 LASTPIN (-1975 3150) BN 12
J 2
(-1963 3158);
DISPLAY 0.680851 (-1963 3158);
PAINT MONO (-1963 3158);
FORCEPROP 1 LAST PATH I42
J 2
(-2023 3150);
DISPLAY 0.872340 (-2023 3150);
PAINT GREEN (-2023 3150);
DISPLAY INVISIBLE (-2023 3150);
FORCEPROP 1 LAST HDL_TAP TRUE
J 2
(-2350 3025);
DISPLAY 0.872340 (-2350 3025);
DISPLAY INVISIBLE (-2350 3025);
FORCEPROP 1 LAST BODY_TYPE PLUMBING
J 2
(-2025 3200);
DISPLAY 0.872340 (-2025 3200);
PAINT GREEN (-2025 3200);
DISPLAY INVISIBLE (-2025 3200);
FORCEPROP 2 LAST CDS_LIB standard
J 0
(-2025 3150);
DISPLAY INVISIBLE (-2025 3150);
FORCEADD TAP..1
R 2
(-2025 3100);
FORCEPROP 3 LASTPIN (-1975 3100) SIG_NAME M_BMC_DDR4_MA<13>
J 0
(-1965 3110);
DISPLAY 0.659574 (-1965 3110);
PAINT MONO (-1965 3110);
DISPLAY INVISIBLE (-1965 3110);
FORCEPROP 1 LASTPIN (-1975 3100) BN 13
J 2
(-1963 3108);
DISPLAY 0.680851 (-1963 3108);
PAINT MONO (-1963 3108);
FORCEPROP 1 LAST PATH I43
J 2
(-2023 3100);
DISPLAY 0.872340 (-2023 3100);
PAINT GREEN (-2023 3100);
DISPLAY INVISIBLE (-2023 3100);
FORCEPROP 1 LAST HDL_TAP TRUE
J 2
(-2350 2975);
DISPLAY 0.872340 (-2350 2975);
DISPLAY INVISIBLE (-2350 2975);
FORCEPROP 1 LAST BODY_TYPE PLUMBING
J 2
(-2025 3150);
DISPLAY 0.872340 (-2025 3150);
PAINT GREEN (-2025 3150);
DISPLAY INVISIBLE (-2025 3150);
FORCEPROP 2 LAST CDS_LIB standard
J 0
(-2025 3100);
DISPLAY INVISIBLE (-2025 3100);
FORCEADD TAP..1
R 2
(-2025 3250);
FORCEPROP 3 LASTPIN (-1975 3250) SIG_NAME M_BMC_DDR4_MA<10>
J 0
(-1965 3260);
DISPLAY 0.659574 (-1965 3260);
PAINT MONO (-1965 3260);
DISPLAY INVISIBLE (-1965 3260);
FORCEPROP 1 LASTPIN (-1975 3250) BN 10
J 2
(-1963 3258);
DISPLAY 0.680851 (-1963 3258);
PAINT MONO (-1963 3258);
FORCEPROP 1 LAST PATH I44
J 2
(-2023 3250);
DISPLAY 0.872340 (-2023 3250);
PAINT GREEN (-2023 3250);
DISPLAY INVISIBLE (-2023 3250);
FORCEPROP 1 LAST HDL_TAP TRUE
J 2
(-2350 3125);
DISPLAY 0.872340 (-2350 3125);
DISPLAY INVISIBLE (-2350 3125);
FORCEPROP 1 LAST BODY_TYPE PLUMBING
J 2
(-2025 3300);
DISPLAY 0.872340 (-2025 3300);
PAINT GREEN (-2025 3300);
DISPLAY INVISIBLE (-2025 3300);
FORCEPROP 2 LAST CDS_LIB standard
J 0
(-2025 3250);
DISPLAY INVISIBLE (-2025 3250);
FORCEADD TAP..1
R 2
(-2025 3300);
FORCEPROP 3 LASTPIN (-1975 3300) SIG_NAME M_BMC_DDR4_MA<9>
J 0
(-1965 3310);
DISPLAY 0.659574 (-1965 3310);
PAINT MONO (-1965 3310);
DISPLAY INVISIBLE (-1965 3310);
FORCEPROP 1 LASTPIN (-1975 3300) BN 9
J 2
(-1963 3308);
DISPLAY 0.680851 (-1963 3308);
PAINT MONO (-1963 3308);
FORCEPROP 1 LAST PATH I45
J 2
(-2023 3300);
DISPLAY 0.872340 (-2023 3300);
PAINT GREEN (-2023 3300);
DISPLAY INVISIBLE (-2023 3300);
FORCEPROP 1 LAST HDL_TAP TRUE
J 2
(-2350 3175);
DISPLAY 0.872340 (-2350 3175);
DISPLAY INVISIBLE (-2350 3175);
FORCEPROP 1 LAST BODY_TYPE PLUMBING
J 2
(-2025 3350);
DISPLAY 0.872340 (-2025 3350);
PAINT GREEN (-2025 3350);
DISPLAY INVISIBLE (-2025 3350);
FORCEPROP 2 LAST CDS_LIB standard
J 0
(-2025 3300);
DISPLAY INVISIBLE (-2025 3300);
FORCEADD TAP..1
R 2
(-2025 3450);
FORCEPROP 3 LASTPIN (-1975 3450) SIG_NAME M_BMC_DDR4_MA<6>
J 0
(-1965 3460);
DISPLAY 0.659574 (-1965 3460);
PAINT MONO (-1965 3460);
DISPLAY INVISIBLE (-1965 3460);
FORCEPROP 1 LASTPIN (-1975 3450) BN 6
J 2
(-1963 3458);
DISPLAY 0.680851 (-1963 3458);
PAINT MONO (-1963 3458);
FORCEPROP 1 LAST PATH I46
J 2
(-2023 3450);
DISPLAY 0.872340 (-2023 3450);
PAINT GREEN (-2023 3450);
DISPLAY INVISIBLE (-2023 3450);
FORCEPROP 1 LAST HDL_TAP TRUE
J 2
(-2350 3325);
DISPLAY 0.872340 (-2350 3325);
DISPLAY INVISIBLE (-2350 3325);
FORCEPROP 1 LAST BODY_TYPE PLUMBING
J 2
(-2025 3500);
DISPLAY 0.872340 (-2025 3500);
PAINT GREEN (-2025 3500);
DISPLAY INVISIBLE (-2025 3500);
FORCEPROP 2 LAST CDS_LIB standard
J 0
(-2025 3450);
DISPLAY INVISIBLE (-2025 3450);
FORCEADD TAP..1
R 2
(-2025 3400);
FORCEPROP 3 LASTPIN (-1975 3400) SIG_NAME M_BMC_DDR4_MA<7>
J 0
(-1965 3410);
DISPLAY 0.659574 (-1965 3410);
PAINT MONO (-1965 3410);
DISPLAY INVISIBLE (-1965 3410);
FORCEPROP 1 LASTPIN (-1975 3400) BN 7
J 2
(-1963 3408);
DISPLAY 0.680851 (-1963 3408);
PAINT MONO (-1963 3408);
FORCEPROP 1 LAST PATH I47
J 2
(-2023 3400);
DISPLAY 0.872340 (-2023 3400);
PAINT GREEN (-2023 3400);
DISPLAY INVISIBLE (-2023 3400);
FORCEPROP 1 LAST HDL_TAP TRUE
J 2
(-2350 3275);
DISPLAY 0.872340 (-2350 3275);
DISPLAY INVISIBLE (-2350 3275);
FORCEPROP 1 LAST BODY_TYPE PLUMBING
J 2
(-2025 3450);
DISPLAY 0.872340 (-2025 3450);
PAINT GREEN (-2025 3450);
DISPLAY INVISIBLE (-2025 3450);
FORCEPROP 2 LAST CDS_LIB standard
J 0
(-2025 3400);
DISPLAY INVISIBLE (-2025 3400);
FORCEADD TAP..1
R 2
(-2025 3350);
FORCEPROP 3 LASTPIN (-1975 3350) SIG_NAME M_BMC_DDR4_MA<8>
J 0
(-1965 3360);
DISPLAY 0.659574 (-1965 3360);
PAINT MONO (-1965 3360);
DISPLAY INVISIBLE (-1965 3360);
FORCEPROP 1 LASTPIN (-1975 3350) BN 8
J 2
(-1963 3358);
DISPLAY 0.680851 (-1963 3358);
PAINT MONO (-1963 3358);
FORCEPROP 1 LAST PATH I48
J 2
(-2023 3350);
DISPLAY 0.872340 (-2023 3350);
PAINT GREEN (-2023 3350);
DISPLAY INVISIBLE (-2023 3350);
FORCEPROP 1 LAST HDL_TAP TRUE
J 2
(-2350 3225);
DISPLAY 0.872340 (-2350 3225);
DISPLAY INVISIBLE (-2350 3225);
FORCEPROP 1 LAST BODY_TYPE PLUMBING
J 2
(-2025 3400);
DISPLAY 0.872340 (-2025 3400);
PAINT GREEN (-2025 3400);
DISPLAY INVISIBLE (-2025 3400);
FORCEPROP 2 LAST CDS_LIB standard
J 0
(-2025 3350);
DISPLAY INVISIBLE (-2025 3350);
FORCEADD OFFPAGE..1
(-2550 4200);
FORCEPROP 2 LAST $XR1 20 
J 0
(-2861 4200);
DISPLAY 0.638298 (-2861 4200);
PAINT MONO (-2861 4200);
FORCEPROP 2 LAST $XR0 12 
J 0
(-2771 4200);
DISPLAY 0.638298 (-2771 4200);
PAINT MONO (-2771 4200);
FORCEPROP 2 LAST PATH I49
J 0
(-2725 4250);
DISPLAY 1.021277 (-2725 4250);
DISPLAY INVISIBLE (-2725 4250);
FORCEPROP 1 LAST COMMENT_BODY TRUE
J 0
(-2425 4100);
DISPLAY 0.872340 (-2425 4100);
PAINT PEACH (-2425 4100);
DISPLAY INVISIBLE (-2425 4100);
FORCEPROP 1 LAST OFFPAGE TRUE
J 0
(-2225 4075);
DISPLAY 0.872340 (-2225 4075);
PAINT GREEN (-2225 4075);
DISPLAY INVISIBLE (-2225 4075);
FORCEPROP 2 LAST CDS_LIB standard
J 0
(-2550 4200);
DISPLAY INVISIBLE (-2550 4200);
FORCEADD Q_CAP..1
(-3475 2475);
FORCEPROP 1 LAST MATERIAL X6S
J 0
(-3425 2375);
DISPLAY 0.510638 (-3425 2375);
PAINT SKYBLUE (-3425 2375);
FORCEPROP 1 LAST TOLERANCE 10%
J 0
(-3425 2425);
DISPLAY 0.510638 (-3425 2425);
PAINT SKYBLUE (-3425 2425);
FORCEPROP 1 LAST VOLTAGE 25V
J 0
(-3425 2475);
DISPLAY 0.510638 (-3425 2475);
PAINT SKYBLUE (-3425 2475);
FORCEPROP 1 LAST VALUE 1UF
J 0
(-3425 2525);
DISPLAY 0.510638 (-3425 2525);
PAINT SKYBLUE (-3425 2525);
FORCEPROP 1 LAST PART_NUMBER CH5104KEB02
J 0
(-3425 2125);
DISPLAY 0.510638 (-3425 2125);
PAINT WHITE (-3425 2125);
FORCEPROP 1 LAST PACK_TYPE C0402
J 0
(-3450 2325);
DISPLAY 0.510638 (-3450 2325);
PAINT SKYBLUE (-3450 2325);
FORCEPROP 1 LAST PATH I5
J 0
(-3425 2625);
DISPLAY 0.978723 (-3425 2625);
PAINT WHITE (-3425 2625);
DISPLAY INVISIBLE (-3425 2625);
FORCEPROP 2 LAST CDS_LIB pure_quanta
J 0
(-3475 2475);
DISPLAY INVISIBLE (-3475 2475);
FORCEPROP 2 LAST SEC_TYPE C0402
J 0
(-3425 2675);
DISPLAY 0.680851 (-3425 2675);
DISPLAY INVISIBLE (-3425 2675);
FORCEPROP 1 LAST LOCATION C2
J 0
(-3425 2575);
DISPLAY 0.702128 (-3425 2575);
PAINT YELLOW (-3425 2575);
FORCEPROP 1 LASTPIN (-3475 2575) $PN 1
J 0
(-3465 2555);
DISPLAY 0.808511 (-3465 2555);
PAINT WHITE (-3465 2555);
FORCEPROP 1 LASTPIN (-3475 2375) $PN 2
J 0
(-3465 2355);
DISPLAY 0.808511 (-3465 2355);
PAINT WHITE (-3465 2355);
FORCEPROP 2 LAST SEC 1
J 0
(-3425 2675);
DISPLAY 0.680851 (-3425 2675);
PAINT MONO (-3425 2675);
DISPLAY INVISIBLE (-3425 2675);
FORCEADD OFFPAGE..1
(-2550 4250);
FORCEPROP 2 LAST $XR1 20 
J 0
(-2861 4250);
DISPLAY 0.638298 (-2861 4250);
PAINT MONO (-2861 4250);
FORCEPROP 2 LAST $XR0 12 
J 0
(-2771 4250);
DISPLAY 0.638298 (-2771 4250);
PAINT MONO (-2771 4250);
FORCEPROP 2 LAST PATH I50
J 0
(-2725 4300);
DISPLAY 1.021277 (-2725 4300);
DISPLAY INVISIBLE (-2725 4300);
FORCEPROP 1 LAST COMMENT_BODY TRUE
J 0
(-2425 4150);
DISPLAY 0.872340 (-2425 4150);
PAINT PEACH (-2425 4150);
DISPLAY INVISIBLE (-2425 4150);
FORCEPROP 1 LAST OFFPAGE TRUE
J 0
(-2225 4125);
DISPLAY 0.872340 (-2225 4125);
PAINT GREEN (-2225 4125);
DISPLAY INVISIBLE (-2225 4125);
FORCEPROP 2 LAST CDS_LIB standard
J 0
(-2550 4250);
DISPLAY INVISIBLE (-2550 4250);
FORCEADD OFFPAGE..1
(-2550 4350);
FORCEPROP 2 LAST $XR1 20 
J 0
(-2861 4350);
DISPLAY 0.638298 (-2861 4350);
PAINT MONO (-2861 4350);
FORCEPROP 2 LAST $XR0 12 
J 0
(-2771 4350);
DISPLAY 0.638298 (-2771 4350);
PAINT MONO (-2771 4350);
FORCEPROP 2 LAST PATH I51
J 0
(-2725 4400);
DISPLAY 1.021277 (-2725 4400);
DISPLAY INVISIBLE (-2725 4400);
FORCEPROP 1 LAST COMMENT_BODY TRUE
J 0
(-2425 4250);
DISPLAY 0.872340 (-2425 4250);
PAINT PEACH (-2425 4250);
DISPLAY INVISIBLE (-2425 4250);
FORCEPROP 1 LAST OFFPAGE TRUE
J 0
(-2225 4225);
DISPLAY 0.872340 (-2225 4225);
PAINT GREEN (-2225 4225);
DISPLAY INVISIBLE (-2225 4225);
FORCEPROP 2 LAST CDS_LIB standard
J 0
(-2550 4350);
DISPLAY INVISIBLE (-2550 4350);
FORCEADD OFFPAGE..1
(-2550 4300);
FORCEPROP 2 LAST $XR1 20 
J 0
(-2861 4300);
DISPLAY 0.638298 (-2861 4300);
PAINT MONO (-2861 4300);
FORCEPROP 2 LAST $XR0 12 
J 0
(-2771 4300);
DISPLAY 0.638298 (-2771 4300);
PAINT MONO (-2771 4300);
FORCEPROP 2 LAST PATH I52
J 0
(-2725 4350);
DISPLAY 1.021277 (-2725 4350);
DISPLAY INVISIBLE (-2725 4350);
FORCEPROP 1 LAST COMMENT_BODY TRUE
J 0
(-2425 4200);
DISPLAY 0.872340 (-2425 4200);
PAINT PEACH (-2425 4200);
DISPLAY INVISIBLE (-2425 4200);
FORCEPROP 1 LAST OFFPAGE TRUE
J 0
(-2225 4175);
DISPLAY 0.872340 (-2225 4175);
PAINT GREEN (-2225 4175);
DISPLAY INVISIBLE (-2225 4175);
FORCEPROP 2 LAST CDS_LIB standard
J 0
(-2550 4300);
DISPLAY INVISIBLE (-2550 4300);
FORCEADD OFFPAGE..1
(-2550 4400);
FORCEPROP 2 LAST $XR1 20 
J 0
(-2861 4400);
DISPLAY 0.638298 (-2861 4400);
PAINT MONO (-2861 4400);
FORCEPROP 2 LAST $XR0 12 
J 0
(-2771 4400);
DISPLAY 0.638298 (-2771 4400);
PAINT MONO (-2771 4400);
FORCEPROP 2 LAST PATH I53
J 0
(-2725 4450);
DISPLAY 1.021277 (-2725 4450);
DISPLAY INVISIBLE (-2725 4450);
FORCEPROP 1 LAST COMMENT_BODY TRUE
J 0
(-2425 4300);
DISPLAY 0.872340 (-2425 4300);
PAINT PEACH (-2425 4300);
DISPLAY INVISIBLE (-2425 4300);
FORCEPROP 1 LAST OFFPAGE TRUE
J 0
(-2225 4275);
DISPLAY 0.872340 (-2225 4275);
PAINT GREEN (-2225 4275);
DISPLAY INVISIBLE (-2225 4275);
FORCEPROP 2 LAST CDS_LIB standard
J 0
(-2550 4400);
DISPLAY INVISIBLE (-2550 4400);
FORCEADD OFFPAGE..1
(-2550 4450);
FORCEPROP 2 LAST $XR1 20 
J 0
(-2861 4450);
DISPLAY 0.638298 (-2861 4450);
PAINT MONO (-2861 4450);
FORCEPROP 2 LAST $XR0 12 
J 0
(-2771 4450);
DISPLAY 0.638298 (-2771 4450);
PAINT MONO (-2771 4450);
FORCEPROP 2 LAST PATH I54
J 0
(-2725 4500);
DISPLAY 1.021277 (-2725 4500);
DISPLAY INVISIBLE (-2725 4500);
FORCEPROP 1 LAST COMMENT_BODY TRUE
J 0
(-2425 4350);
DISPLAY 0.872340 (-2425 4350);
PAINT PEACH (-2425 4350);
DISPLAY INVISIBLE (-2425 4350);
FORCEPROP 1 LAST OFFPAGE TRUE
J 0
(-2225 4325);
DISPLAY 0.872340 (-2225 4325);
PAINT GREEN (-2225 4325);
DISPLAY INVISIBLE (-2225 4325);
FORCEPROP 2 LAST CDS_LIB standard
J 0
(-2550 4450);
DISPLAY INVISIBLE (-2550 4450);
FORCEADD OFFPAGE..1
(-2550 4500);
FORCEPROP 2 LAST $XR1 20 
J 0
(-2861 4500);
DISPLAY 0.638298 (-2861 4500);
PAINT MONO (-2861 4500);
FORCEPROP 2 LAST $XR0 12 
J 0
(-2771 4500);
DISPLAY 0.638298 (-2771 4500);
PAINT MONO (-2771 4500);
FORCEPROP 2 LAST PATH I55
J 0
(-2725 4550);
DISPLAY 1.021277 (-2725 4550);
DISPLAY INVISIBLE (-2725 4550);
FORCEPROP 1 LAST COMMENT_BODY TRUE
J 0
(-2425 4400);
DISPLAY 0.872340 (-2425 4400);
PAINT PEACH (-2425 4400);
DISPLAY INVISIBLE (-2425 4400);
FORCEPROP 1 LAST OFFPAGE TRUE
J 0
(-2225 4375);
DISPLAY 0.872340 (-2225 4375);
PAINT GREEN (-2225 4375);
DISPLAY INVISIBLE (-2225 4375);
FORCEPROP 2 LAST CDS_LIB standard
J 0
(-2550 4500);
DISPLAY INVISIBLE (-2550 4500);
FORCEADD TAP..1
R 2
(-2025 3550);
FORCEPROP 3 LASTPIN (-1975 3550) SIG_NAME M_BMC_DDR4_MA<4>
J 0
(-1965 3560);
DISPLAY 0.659574 (-1965 3560);
PAINT MONO (-1965 3560);
DISPLAY INVISIBLE (-1965 3560);
FORCEPROP 1 LASTPIN (-1975 3550) BN 4
J 2
(-1963 3558);
DISPLAY 0.680851 (-1963 3558);
PAINT MONO (-1963 3558);
FORCEPROP 1 LAST PATH I56
J 2
(-2023 3550);
DISPLAY 0.872340 (-2023 3550);
PAINT GREEN (-2023 3550);
DISPLAY INVISIBLE (-2023 3550);
FORCEPROP 1 LAST HDL_TAP TRUE
J 2
(-2350 3425);
DISPLAY 0.872340 (-2350 3425);
DISPLAY INVISIBLE (-2350 3425);
FORCEPROP 1 LAST BODY_TYPE PLUMBING
J 2
(-2025 3600);
DISPLAY 0.872340 (-2025 3600);
PAINT GREEN (-2025 3600);
DISPLAY INVISIBLE (-2025 3600);
FORCEPROP 2 LAST CDS_LIB standard
J 0
(-2025 3550);
DISPLAY INVISIBLE (-2025 3550);
FORCEADD TAP..1
R 2
(-2025 3500);
FORCEPROP 3 LASTPIN (-1975 3500) SIG_NAME M_BMC_DDR4_MA<5>
J 0
(-1965 3510);
DISPLAY 0.659574 (-1965 3510);
PAINT MONO (-1965 3510);
DISPLAY INVISIBLE (-1965 3510);
FORCEPROP 1 LASTPIN (-1975 3500) BN 5
J 2
(-1963 3508);
DISPLAY 0.680851 (-1963 3508);
PAINT MONO (-1963 3508);
FORCEPROP 1 LAST PATH I57
J 2
(-2023 3500);
DISPLAY 0.872340 (-2023 3500);
PAINT GREEN (-2023 3500);
DISPLAY INVISIBLE (-2023 3500);
FORCEPROP 1 LAST HDL_TAP TRUE
J 2
(-2350 3375);
DISPLAY 0.872340 (-2350 3375);
DISPLAY INVISIBLE (-2350 3375);
FORCEPROP 1 LAST BODY_TYPE PLUMBING
J 2
(-2025 3550);
DISPLAY 0.872340 (-2025 3550);
PAINT GREEN (-2025 3550);
DISPLAY INVISIBLE (-2025 3550);
FORCEPROP 2 LAST CDS_LIB standard
J 0
(-2025 3500);
DISPLAY INVISIBLE (-2025 3500);
FORCEADD TAP..1
R 2
(-2025 3700);
FORCEPROP 3 LASTPIN (-1975 3700) SIG_NAME M_BMC_DDR4_MA<1>
J 0
(-1965 3710);
DISPLAY 0.659574 (-1965 3710);
PAINT MONO (-1965 3710);
DISPLAY INVISIBLE (-1965 3710);
FORCEPROP 1 LASTPIN (-1975 3700) BN 1
J 2
(-1963 3708);
DISPLAY 0.680851 (-1963 3708);
PAINT MONO (-1963 3708);
FORCEPROP 1 LAST PATH I58
J 2
(-2023 3700);
DISPLAY 0.872340 (-2023 3700);
PAINT GREEN (-2023 3700);
DISPLAY INVISIBLE (-2023 3700);
FORCEPROP 1 LAST HDL_TAP TRUE
J 2
(-2350 3575);
DISPLAY 0.872340 (-2350 3575);
DISPLAY INVISIBLE (-2350 3575);
FORCEPROP 1 LAST BODY_TYPE PLUMBING
J 2
(-2025 3750);
DISPLAY 0.872340 (-2025 3750);
PAINT GREEN (-2025 3750);
DISPLAY INVISIBLE (-2025 3750);
FORCEPROP 2 LAST CDS_LIB standard
J 0
(-2025 3700);
DISPLAY INVISIBLE (-2025 3700);
FORCEADD TAP..1
R 2
(-2025 3650);
FORCEPROP 3 LASTPIN (-1975 3650) SIG_NAME M_BMC_DDR4_MA<2>
J 0
(-1965 3660);
DISPLAY 0.659574 (-1965 3660);
PAINT MONO (-1965 3660);
DISPLAY INVISIBLE (-1965 3660);
FORCEPROP 1 LASTPIN (-1975 3650) BN 2
J 2
(-1963 3658);
DISPLAY 0.680851 (-1963 3658);
PAINT MONO (-1963 3658);
FORCEPROP 1 LAST PATH I59
J 2
(-2023 3650);
DISPLAY 0.872340 (-2023 3650);
PAINT GREEN (-2023 3650);
DISPLAY INVISIBLE (-2023 3650);
FORCEPROP 1 LAST HDL_TAP TRUE
J 2
(-2350 3525);
DISPLAY 0.872340 (-2350 3525);
DISPLAY INVISIBLE (-2350 3525);
FORCEPROP 1 LAST BODY_TYPE PLUMBING
J 2
(-2025 3700);
DISPLAY 0.872340 (-2025 3700);
PAINT GREEN (-2025 3700);
DISPLAY INVISIBLE (-2025 3700);
FORCEPROP 2 LAST CDS_LIB standard
J 0
(-2025 3650);
DISPLAY INVISIBLE (-2025 3650);
FORCEADD Q_CAP..1
(-3275 2475);
FORCEPROP 1 LAST VOLTAGE 25V
J 0
(-3225 2475);
DISPLAY 0.510638 (-3225 2475);
PAINT SKYBLUE (-3225 2475);
FORCEPROP 1 LAST VALUE 1UF
J 0
(-3225 2525);
DISPLAY 0.510638 (-3225 2525);
PAINT SKYBLUE (-3225 2525);
FORCEPROP 1 LAST MATERIAL X6S
J 0
(-3225 2375);
DISPLAY 0.510638 (-3225 2375);
PAINT SKYBLUE (-3225 2375);
FORCEPROP 1 LAST TOLERANCE 10%
J 0
(-3225 2425);
DISPLAY 0.510638 (-3225 2425);
PAINT SKYBLUE (-3225 2425);
FORCEPROP 1 LAST PACK_TYPE C0402
J 0
(-3250 2325);
DISPLAY 0.510638 (-3250 2325);
PAINT SKYBLUE (-3250 2325);
FORCEPROP 1 LAST PATH I6
J 0
(-3225 2625);
DISPLAY 0.978723 (-3225 2625);
PAINT WHITE (-3225 2625);
DISPLAY INVISIBLE (-3225 2625);
FORCEPROP 2 LAST CDS_LIB pure_quanta
J 0
(-3275 2475);
DISPLAY INVISIBLE (-3275 2475);
FORCEPROP 2 LAST SEC_TYPE C0402
J 0
(-3225 2675);
DISPLAY 0.680851 (-3225 2675);
DISPLAY INVISIBLE (-3225 2675);
FORCEPROP 1 LAST PART_NUMBER CH5104KEB02
J 0
(-3225 2325);
DISPLAY 0.510638 (-3225 2325);
PAINT WHITE (-3225 2325);
DISPLAY INVISIBLE (-3225 2325);
FORCEPROP 1 LAST LOCATION C3
J 0
(-3225 2575);
DISPLAY 0.702128 (-3225 2575);
PAINT YELLOW (-3225 2575);
FORCEPROP 1 LASTPIN (-3275 2575) $PN 1
J 0
(-3265 2555);
DISPLAY 0.808511 (-3265 2555);
PAINT WHITE (-3265 2555);
FORCEPROP 1 LASTPIN (-3275 2375) $PN 2
J 0
(-3265 2355);
DISPLAY 0.808511 (-3265 2355);
PAINT WHITE (-3265 2355);
FORCEPROP 2 LAST SEC 1
J 0
(-3225 2675);
DISPLAY 0.680851 (-3225 2675);
PAINT MONO (-3225 2675);
DISPLAY INVISIBLE (-3225 2675);
FORCEADD TAP..1
R 2
(-2025 3600);
FORCEPROP 3 LASTPIN (-1975 3600) SIG_NAME M_BMC_DDR4_MA<3>
J 0
(-1965 3610);
DISPLAY 0.659574 (-1965 3610);
PAINT MONO (-1965 3610);
DISPLAY INVISIBLE (-1965 3610);
FORCEPROP 1 LASTPIN (-1975 3600) BN 3
J 2
(-1963 3608);
DISPLAY 0.680851 (-1963 3608);
PAINT MONO (-1963 3608);
FORCEPROP 1 LAST PATH I60
J 2
(-2023 3600);
DISPLAY 0.872340 (-2023 3600);
PAINT GREEN (-2023 3600);
DISPLAY INVISIBLE (-2023 3600);
FORCEPROP 1 LAST HDL_TAP TRUE
J 2
(-2350 3475);
DISPLAY 0.872340 (-2350 3475);
DISPLAY INVISIBLE (-2350 3475);
FORCEPROP 1 LAST BODY_TYPE PLUMBING
J 2
(-2025 3650);
DISPLAY 0.872340 (-2025 3650);
PAINT GREEN (-2025 3650);
DISPLAY INVISIBLE (-2025 3650);
FORCEPROP 2 LAST CDS_LIB standard
J 0
(-2025 3600);
DISPLAY INVISIBLE (-2025 3600);
FORCEADD TAP..1
R 2
(-2025 3750);
FORCEPROP 3 LASTPIN (-1975 3750) SIG_NAME M_BMC_DDR4_MA<0>
J 0
(-1965 3760);
DISPLAY 0.659574 (-1965 3760);
PAINT MONO (-1965 3760);
DISPLAY INVISIBLE (-1965 3760);
FORCEPROP 1 LASTPIN (-1975 3750) BN 0
J 2
(-1963 3758);
DISPLAY 0.680851 (-1963 3758);
PAINT MONO (-1963 3758);
FORCEPROP 1 LAST PATH I61
J 2
(-2023 3750);
DISPLAY 0.872340 (-2023 3750);
PAINT GREEN (-2023 3750);
DISPLAY INVISIBLE (-2023 3750);
FORCEPROP 1 LAST HDL_TAP TRUE
J 2
(-2350 3625);
DISPLAY 0.872340 (-2350 3625);
DISPLAY INVISIBLE (-2350 3625);
FORCEPROP 1 LAST BODY_TYPE PLUMBING
J 2
(-2025 3800);
DISPLAY 0.872340 (-2025 3800);
PAINT GREEN (-2025 3800);
DISPLAY INVISIBLE (-2025 3800);
FORCEPROP 2 LAST CDS_LIB standard
J 0
(-2025 3750);
DISPLAY INVISIBLE (-2025 3750);
FORCEADD TAP..1
(50 3750);
FORCEPROP 3 LASTPIN (0 3750) SIG_NAME M_BMC_DDR4_DQ<15>
J 0
(10 3760);
DISPLAY 0.659574 (10 3760);
PAINT MONO (10 3760);
DISPLAY INVISIBLE (10 3760);
FORCEPROP 1 LASTPIN (0 3750) BN 15
J 0
(-12 3758);
DISPLAY 0.680851 (-12 3758);
PAINT MONO (-12 3758);
FORCEPROP 1 LAST PATH I62
J 0
(48 3750);
DISPLAY 0.872340 (48 3750);
PAINT GREEN (48 3750);
DISPLAY INVISIBLE (48 3750);
FORCEPROP 1 LAST HDL_TAP TRUE
J 0
(375 3625);
DISPLAY 0.872340 (375 3625);
DISPLAY INVISIBLE (375 3625);
FORCEPROP 1 LAST BODY_TYPE PLUMBING
J 0
(50 3800);
DISPLAY 0.872340 (50 3800);
PAINT GREEN (50 3800);
DISPLAY INVISIBLE (50 3800);
FORCEPROP 2 LAST CDS_LIB standard
J 0
(50 3750);
DISPLAY INVISIBLE (50 3750);
FORCEADD TAP..1
(50 3850);
FORCEPROP 3 LASTPIN (0 3850) SIG_NAME M_BMC_DDR4_DQ<13>
J 0
(10 3860);
DISPLAY 0.659574 (10 3860);
PAINT MONO (10 3860);
DISPLAY INVISIBLE (10 3860);
FORCEPROP 1 LASTPIN (0 3850) BN 13
J 0
(-12 3858);
DISPLAY 0.680851 (-12 3858);
PAINT MONO (-12 3858);
FORCEPROP 1 LAST PATH I63
J 0
(48 3850);
DISPLAY 0.872340 (48 3850);
PAINT GREEN (48 3850);
DISPLAY INVISIBLE (48 3850);
FORCEPROP 1 LAST HDL_TAP TRUE
J 0
(375 3725);
DISPLAY 0.872340 (375 3725);
DISPLAY INVISIBLE (375 3725);
FORCEPROP 1 LAST BODY_TYPE PLUMBING
J 0
(50 3900);
DISPLAY 0.872340 (50 3900);
PAINT GREEN (50 3900);
DISPLAY INVISIBLE (50 3900);
FORCEPROP 2 LAST CDS_LIB standard
J 0
(50 3850);
DISPLAY INVISIBLE (50 3850);
FORCEADD TAP..1
(50 3800);
FORCEPROP 3 LASTPIN (0 3800) SIG_NAME M_BMC_DDR4_DQ<14>
J 0
(10 3810);
DISPLAY 0.659574 (10 3810);
PAINT MONO (10 3810);
DISPLAY INVISIBLE (10 3810);
FORCEPROP 1 LASTPIN (0 3800) BN 14
J 0
(-12 3808);
DISPLAY 0.680851 (-12 3808);
PAINT MONO (-12 3808);
FORCEPROP 1 LAST PATH I64
J 0
(48 3800);
DISPLAY 0.872340 (48 3800);
PAINT GREEN (48 3800);
DISPLAY INVISIBLE (48 3800);
FORCEPROP 1 LAST HDL_TAP TRUE
J 0
(375 3675);
DISPLAY 0.872340 (375 3675);
DISPLAY INVISIBLE (375 3675);
FORCEPROP 1 LAST BODY_TYPE PLUMBING
J 0
(50 3850);
DISPLAY 0.872340 (50 3850);
PAINT GREEN (50 3850);
DISPLAY INVISIBLE (50 3850);
FORCEPROP 2 LAST CDS_LIB standard
J 0
(50 3800);
DISPLAY INVISIBLE (50 3800);
FORCEADD TAP..1
(50 4000);
FORCEPROP 3 LASTPIN (0 4000) SIG_NAME M_BMC_DDR4_DQ<10>
J 0
(10 4010);
DISPLAY 0.659574 (10 4010);
PAINT MONO (10 4010);
DISPLAY INVISIBLE (10 4010);
FORCEPROP 1 LASTPIN (0 4000) BN 10
J 0
(-12 4008);
DISPLAY 0.680851 (-12 4008);
PAINT MONO (-12 4008);
FORCEPROP 1 LAST PATH I65
J 0
(48 4000);
DISPLAY 0.872340 (48 4000);
PAINT GREEN (48 4000);
DISPLAY INVISIBLE (48 4000);
FORCEPROP 1 LAST HDL_TAP TRUE
J 0
(375 3875);
DISPLAY 0.872340 (375 3875);
DISPLAY INVISIBLE (375 3875);
FORCEPROP 1 LAST BODY_TYPE PLUMBING
J 0
(50 4050);
DISPLAY 0.872340 (50 4050);
PAINT GREEN (50 4050);
DISPLAY INVISIBLE (50 4050);
FORCEPROP 2 LAST CDS_LIB standard
J 0
(50 4000);
DISPLAY INVISIBLE (50 4000);
FORCEADD TAP..1
(50 3950);
FORCEPROP 3 LASTPIN (0 3950) SIG_NAME M_BMC_DDR4_DQ<11>
J 0
(10 3960);
DISPLAY 0.659574 (10 3960);
PAINT MONO (10 3960);
DISPLAY INVISIBLE (10 3960);
FORCEPROP 1 LASTPIN (0 3950) BN 11
J 0
(-12 3958);
DISPLAY 0.680851 (-12 3958);
PAINT MONO (-12 3958);
FORCEPROP 1 LAST PATH I66
J 0
(48 3950);
DISPLAY 0.872340 (48 3950);
PAINT GREEN (48 3950);
DISPLAY INVISIBLE (48 3950);
FORCEPROP 1 LAST HDL_TAP TRUE
J 0
(375 3825);
DISPLAY 0.872340 (375 3825);
DISPLAY INVISIBLE (375 3825);
FORCEPROP 1 LAST BODY_TYPE PLUMBING
J 0
(50 4000);
DISPLAY 0.872340 (50 4000);
PAINT GREEN (50 4000);
DISPLAY INVISIBLE (50 4000);
FORCEPROP 2 LAST CDS_LIB standard
J 0
(50 3950);
DISPLAY INVISIBLE (50 3950);
FORCEADD TAP..1
(50 3900);
FORCEPROP 3 LASTPIN (0 3900) SIG_NAME M_BMC_DDR4_DQ<12>
J 0
(10 3910);
DISPLAY 0.659574 (10 3910);
PAINT MONO (10 3910);
DISPLAY INVISIBLE (10 3910);
FORCEPROP 1 LASTPIN (0 3900) BN 12
J 0
(-12 3908);
DISPLAY 0.680851 (-12 3908);
PAINT MONO (-12 3908);
FORCEPROP 1 LAST PATH I67
J 0
(48 3900);
DISPLAY 0.872340 (48 3900);
PAINT GREEN (48 3900);
DISPLAY INVISIBLE (48 3900);
FORCEPROP 1 LAST HDL_TAP TRUE
J 0
(375 3775);
DISPLAY 0.872340 (375 3775);
DISPLAY INVISIBLE (375 3775);
FORCEPROP 1 LAST BODY_TYPE PLUMBING
J 0
(50 3950);
DISPLAY 0.872340 (50 3950);
PAINT GREEN (50 3950);
DISPLAY INVISIBLE (50 3950);
FORCEPROP 2 LAST CDS_LIB standard
J 0
(50 3900);
DISPLAY INVISIBLE (50 3900);
FORCEADD TAP..1
(50 4100);
FORCEPROP 3 LASTPIN (0 4100) SIG_NAME M_BMC_DDR4_DQ<8>
J 0
(10 4110);
DISPLAY 0.659574 (10 4110);
PAINT MONO (10 4110);
DISPLAY INVISIBLE (10 4110);
FORCEPROP 1 LASTPIN (0 4100) BN 8
J 0
(-12 4108);
DISPLAY 0.680851 (-12 4108);
PAINT MONO (-12 4108);
FORCEPROP 1 LAST PATH I68
J 0
(48 4100);
DISPLAY 0.872340 (48 4100);
PAINT GREEN (48 4100);
DISPLAY INVISIBLE (48 4100);
FORCEPROP 1 LAST HDL_TAP TRUE
J 0
(375 3975);
DISPLAY 0.872340 (375 3975);
DISPLAY INVISIBLE (375 3975);
FORCEPROP 1 LAST BODY_TYPE PLUMBING
J 0
(50 4150);
DISPLAY 0.872340 (50 4150);
PAINT GREEN (50 4150);
DISPLAY INVISIBLE (50 4150);
FORCEPROP 2 LAST CDS_LIB standard
J 0
(50 4100);
DISPLAY INVISIBLE (50 4100);
FORCEADD TAP..1
(50 4050);
FORCEPROP 3 LASTPIN (0 4050) SIG_NAME M_BMC_DDR4_DQ<9>
J 0
(10 4060);
DISPLAY 0.659574 (10 4060);
PAINT MONO (10 4060);
DISPLAY INVISIBLE (10 4060);
FORCEPROP 1 LASTPIN (0 4050) BN 9
J 0
(-12 4058);
DISPLAY 0.680851 (-12 4058);
PAINT MONO (-12 4058);
FORCEPROP 1 LAST PATH I69
J 0
(48 4050);
DISPLAY 0.872340 (48 4050);
PAINT GREEN (48 4050);
DISPLAY INVISIBLE (48 4050);
FORCEPROP 1 LAST HDL_TAP TRUE
J 0
(375 3925);
DISPLAY 0.872340 (375 3925);
DISPLAY INVISIBLE (375 3925);
FORCEPROP 1 LAST BODY_TYPE PLUMBING
J 0
(50 4100);
DISPLAY 0.872340 (50 4100);
PAINT GREEN (50 4100);
DISPLAY INVISIBLE (50 4100);
FORCEPROP 2 LAST CDS_LIB standard
J 0
(50 4050);
DISPLAY INVISIBLE (50 4050);
FORCEADD Q_CAP..1
(-3075 2475);
FORCEPROP 1 LAST VOLTAGE 25V
J 0
(-3025 2475);
DISPLAY 0.510638 (-3025 2475);
PAINT SKYBLUE (-3025 2475);
FORCEPROP 1 LAST TOLERANCE 10%
J 0
(-3025 2425);
DISPLAY 0.510638 (-3025 2425);
PAINT SKYBLUE (-3025 2425);
FORCEPROP 1 LAST VALUE 1UF
J 0
(-3025 2525);
DISPLAY 0.510638 (-3025 2525);
PAINT SKYBLUE (-3025 2525);
FORCEPROP 1 LAST MATERIAL X6S
J 0
(-3025 2375);
DISPLAY 0.510638 (-3025 2375);
PAINT SKYBLUE (-3025 2375);
FORCEPROP 1 LAST PACK_TYPE C0402
J 0
(-3050 2325);
DISPLAY 0.510638 (-3050 2325);
PAINT SKYBLUE (-3050 2325);
FORCEPROP 1 LAST PATH I7
J 0
(-3025 2625);
DISPLAY 0.978723 (-3025 2625);
PAINT WHITE (-3025 2625);
DISPLAY INVISIBLE (-3025 2625);
FORCEPROP 2 LAST CDS_LIB pure_quanta
J 0
(-3075 2475);
DISPLAY INVISIBLE (-3075 2475);
FORCEPROP 2 LAST SEC_TYPE C0402
J 0
(-3025 2675);
DISPLAY 0.680851 (-3025 2675);
DISPLAY INVISIBLE (-3025 2675);
FORCEPROP 1 LAST PART_NUMBER CH5104KEB02
J 0
(-3025 2325);
DISPLAY 0.510638 (-3025 2325);
PAINT WHITE (-3025 2325);
DISPLAY INVISIBLE (-3025 2325);
FORCEPROP 1 LAST LOCATION C4
J 0
(-3025 2575);
DISPLAY 0.702128 (-3025 2575);
PAINT YELLOW (-3025 2575);
FORCEPROP 1 LASTPIN (-3075 2575) $PN 1
J 0
(-3065 2555);
DISPLAY 0.808511 (-3065 2555);
PAINT WHITE (-3065 2555);
FORCEPROP 1 LASTPIN (-3075 2375) $PN 2
J 0
(-3065 2355);
DISPLAY 0.808511 (-3065 2355);
PAINT WHITE (-3065 2355);
FORCEPROP 2 LAST SEC 1
J 0
(-3025 2675);
DISPLAY 0.680851 (-3025 2675);
PAINT MONO (-3025 2675);
DISPLAY INVISIBLE (-3025 2675);
FORCEADD TAP..1
(50 4250);
FORCEPROP 3 LASTPIN (0 4250) SIG_NAME M_BMC_DDR4_DQ<5>
J 0
(10 4260);
DISPLAY 0.659574 (10 4260);
PAINT MONO (10 4260);
DISPLAY INVISIBLE (10 4260);
FORCEPROP 1 LASTPIN (0 4250) BN 5
J 0
(-12 4258);
DISPLAY 0.680851 (-12 4258);
PAINT MONO (-12 4258);
FORCEPROP 1 LAST PATH I70
J 0
(48 4250);
DISPLAY 0.872340 (48 4250);
PAINT GREEN (48 4250);
DISPLAY INVISIBLE (48 4250);
FORCEPROP 1 LAST HDL_TAP TRUE
J 0
(375 4125);
DISPLAY 0.872340 (375 4125);
DISPLAY INVISIBLE (375 4125);
FORCEPROP 1 LAST BODY_TYPE PLUMBING
J 0
(50 4300);
DISPLAY 0.872340 (50 4300);
PAINT GREEN (50 4300);
DISPLAY INVISIBLE (50 4300);
FORCEPROP 2 LAST CDS_LIB standard
J 0
(50 4250);
DISPLAY INVISIBLE (50 4250);
FORCEADD TAP..1
(50 4200);
FORCEPROP 3 LASTPIN (0 4200) SIG_NAME M_BMC_DDR4_DQ<6>
J 0
(10 4210);
DISPLAY 0.659574 (10 4210);
PAINT MONO (10 4210);
DISPLAY INVISIBLE (10 4210);
FORCEPROP 1 LASTPIN (0 4200) BN 6
J 0
(-12 4208);
DISPLAY 0.680851 (-12 4208);
PAINT MONO (-12 4208);
FORCEPROP 1 LAST PATH I71
J 0
(48 4200);
DISPLAY 0.872340 (48 4200);
PAINT GREEN (48 4200);
DISPLAY INVISIBLE (48 4200);
FORCEPROP 1 LAST HDL_TAP TRUE
J 0
(375 4075);
DISPLAY 0.872340 (375 4075);
DISPLAY INVISIBLE (375 4075);
FORCEPROP 1 LAST BODY_TYPE PLUMBING
J 0
(50 4250);
DISPLAY 0.872340 (50 4250);
PAINT GREEN (50 4250);
DISPLAY INVISIBLE (50 4250);
FORCEPROP 2 LAST CDS_LIB standard
J 0
(50 4200);
DISPLAY INVISIBLE (50 4200);
FORCEADD TAP..1
(50 4150);
FORCEPROP 3 LASTPIN (0 4150) SIG_NAME M_BMC_DDR4_DQ<7>
J 0
(10 4160);
DISPLAY 0.659574 (10 4160);
PAINT MONO (10 4160);
DISPLAY INVISIBLE (10 4160);
FORCEPROP 1 LASTPIN (0 4150) BN 7
J 0
(-12 4158);
DISPLAY 0.680851 (-12 4158);
PAINT MONO (-12 4158);
FORCEPROP 1 LAST PATH I72
J 0
(48 4150);
DISPLAY 0.872340 (48 4150);
PAINT GREEN (48 4150);
DISPLAY INVISIBLE (48 4150);
FORCEPROP 1 LAST HDL_TAP TRUE
J 0
(375 4025);
DISPLAY 0.872340 (375 4025);
DISPLAY INVISIBLE (375 4025);
FORCEPROP 1 LAST BODY_TYPE PLUMBING
J 0
(50 4200);
DISPLAY 0.872340 (50 4200);
PAINT GREEN (50 4200);
DISPLAY INVISIBLE (50 4200);
FORCEPROP 2 LAST CDS_LIB standard
J 0
(50 4150);
DISPLAY INVISIBLE (50 4150);
FORCEADD TAP..1
(50 4350);
FORCEPROP 3 LASTPIN (0 4350) SIG_NAME M_BMC_DDR4_DQ<3>
J 0
(10 4360);
DISPLAY 0.659574 (10 4360);
PAINT MONO (10 4360);
DISPLAY INVISIBLE (10 4360);
FORCEPROP 1 LASTPIN (0 4350) BN 3
J 0
(-12 4358);
DISPLAY 0.680851 (-12 4358);
PAINT MONO (-12 4358);
FORCEPROP 1 LAST PATH I73
J 0
(48 4350);
DISPLAY 0.872340 (48 4350);
PAINT GREEN (48 4350);
DISPLAY INVISIBLE (48 4350);
FORCEPROP 1 LAST HDL_TAP TRUE
J 0
(375 4225);
DISPLAY 0.872340 (375 4225);
DISPLAY INVISIBLE (375 4225);
FORCEPROP 1 LAST BODY_TYPE PLUMBING
J 0
(50 4400);
DISPLAY 0.872340 (50 4400);
PAINT GREEN (50 4400);
DISPLAY INVISIBLE (50 4400);
FORCEPROP 2 LAST CDS_LIB standard
J 0
(50 4350);
DISPLAY INVISIBLE (50 4350);
FORCEADD TAP..1
(50 4300);
FORCEPROP 3 LASTPIN (0 4300) SIG_NAME M_BMC_DDR4_DQ<4>
J 0
(10 4310);
DISPLAY 0.659574 (10 4310);
PAINT MONO (10 4310);
DISPLAY INVISIBLE (10 4310);
FORCEPROP 1 LASTPIN (0 4300) BN 4
J 0
(-12 4308);
DISPLAY 0.680851 (-12 4308);
PAINT MONO (-12 4308);
FORCEPROP 1 LAST PATH I74
J 0
(48 4300);
DISPLAY 0.872340 (48 4300);
PAINT GREEN (48 4300);
DISPLAY INVISIBLE (48 4300);
FORCEPROP 1 LAST HDL_TAP TRUE
J 0
(375 4175);
DISPLAY 0.872340 (375 4175);
DISPLAY INVISIBLE (375 4175);
FORCEPROP 1 LAST BODY_TYPE PLUMBING
J 0
(50 4350);
DISPLAY 0.872340 (50 4350);
PAINT GREEN (50 4350);
DISPLAY INVISIBLE (50 4350);
FORCEPROP 2 LAST CDS_LIB standard
J 0
(50 4300);
DISPLAY INVISIBLE (50 4300);
FORCEADD TAP..1
(50 4500);
FORCEPROP 3 LASTPIN (0 4500) SIG_NAME M_BMC_DDR4_DQ<0>
J 0
(10 4510);
DISPLAY 0.659574 (10 4510);
PAINT MONO (10 4510);
DISPLAY INVISIBLE (10 4510);
FORCEPROP 1 LASTPIN (0 4500) BN 0
J 0
(-12 4508);
DISPLAY 0.680851 (-12 4508);
PAINT MONO (-12 4508);
FORCEPROP 1 LAST PATH I75
J 0
(48 4500);
DISPLAY 0.872340 (48 4500);
PAINT GREEN (48 4500);
DISPLAY INVISIBLE (48 4500);
FORCEPROP 1 LAST HDL_TAP TRUE
J 0
(375 4375);
DISPLAY 0.872340 (375 4375);
DISPLAY INVISIBLE (375 4375);
FORCEPROP 1 LAST BODY_TYPE PLUMBING
J 0
(50 4550);
DISPLAY 0.872340 (50 4550);
PAINT GREEN (50 4550);
DISPLAY INVISIBLE (50 4550);
FORCEPROP 2 LAST CDS_LIB standard
J 0
(50 4500);
DISPLAY INVISIBLE (50 4500);
FORCEADD TAP..1
(50 4450);
FORCEPROP 3 LASTPIN (0 4450) SIG_NAME M_BMC_DDR4_DQ<1>
J 0
(10 4460);
DISPLAY 0.659574 (10 4460);
PAINT MONO (10 4460);
DISPLAY INVISIBLE (10 4460);
FORCEPROP 1 LASTPIN (0 4450) BN 1
J 0
(-12 4458);
DISPLAY 0.680851 (-12 4458);
PAINT MONO (-12 4458);
FORCEPROP 1 LAST PATH I76
J 0
(48 4450);
DISPLAY 0.872340 (48 4450);
PAINT GREEN (48 4450);
DISPLAY INVISIBLE (48 4450);
FORCEPROP 1 LAST HDL_TAP TRUE
J 0
(375 4325);
DISPLAY 0.872340 (375 4325);
DISPLAY INVISIBLE (375 4325);
FORCEPROP 1 LAST BODY_TYPE PLUMBING
J 0
(50 4500);
DISPLAY 0.872340 (50 4500);
PAINT GREEN (50 4500);
DISPLAY INVISIBLE (50 4500);
FORCEPROP 2 LAST CDS_LIB standard
J 0
(50 4450);
DISPLAY INVISIBLE (50 4450);
FORCEADD TAP..1
(50 4400);
FORCEPROP 3 LASTPIN (0 4400) SIG_NAME M_BMC_DDR4_DQ<2>
J 0
(10 4410);
DISPLAY 0.659574 (10 4410);
PAINT MONO (10 4410);
DISPLAY INVISIBLE (10 4410);
FORCEPROP 1 LASTPIN (0 4400) BN 2
J 0
(-12 4408);
DISPLAY 0.680851 (-12 4408);
PAINT MONO (-12 4408);
FORCEPROP 1 LAST PATH I77
J 0
(48 4400);
DISPLAY 0.872340 (48 4400);
PAINT GREEN (48 4400);
DISPLAY INVISIBLE (48 4400);
FORCEPROP 1 LAST HDL_TAP TRUE
J 0
(375 4275);
DISPLAY 0.872340 (375 4275);
DISPLAY INVISIBLE (375 4275);
FORCEPROP 1 LAST BODY_TYPE PLUMBING
J 0
(50 4450);
DISPLAY 0.872340 (50 4450);
PAINT GREEN (50 4450);
DISPLAY INVISIBLE (50 4450);
FORCEPROP 2 LAST CDS_LIB standard
J 0
(50 4400);
DISPLAY INVISIBLE (50 4400);
FORCEADD OFFPAGE..3
(425 3050);
FORCEPROP 2 LAST $XR1 20 
J 0
(729 3050);
DISPLAY 0.638298 (729 3050);
PAINT MONO (729 3050);
FORCEPROP 2 LAST $XR0 12 
J 0
(639 3050);
DISPLAY 0.638298 (639 3050);
PAINT MONO (639 3050);
FORCEPROP 2 LAST PATH I78
J 0
(700 3100);
DISPLAY 1.021277 (700 3100);
DISPLAY INVISIBLE (700 3100);
FORCEPROP 1 LAST COMMENT_BODY TRUE
J 0
(375 2950);
DISPLAY 0.872340 (375 2950);
PAINT PEACH (375 2950);
DISPLAY INVISIBLE (375 2950);
FORCEPROP 1 LAST OFFPAGE TRUE
J 0
(750 2925);
DISPLAY 0.872340 (750 2925);
PAINT GREEN (750 2925);
DISPLAY INVISIBLE (750 2925);
FORCEPROP 2 LAST CDS_LIB standard
J 0
(425 3050);
DISPLAY INVISIBLE (425 3050);
FORCEADD OFFPAGE..3
(425 3250);
FORCEPROP 2 LAST $XR0 12 
J 0
(639 3250);
DISPLAY 0.638298 (639 3250);
PAINT MONO (639 3250);
FORCEPROP 2 LAST PATH I79
J 0
(650 3300);
DISPLAY 1.021277 (650 3300);
DISPLAY INVISIBLE (650 3300);
FORCEPROP 1 LAST COMMENT_BODY TRUE
J 0
(375 3150);
DISPLAY 0.872340 (375 3150);
PAINT PEACH (375 3150);
DISPLAY INVISIBLE (375 3150);
FORCEPROP 1 LAST OFFPAGE TRUE
J 0
(750 3125);
DISPLAY 0.872340 (750 3125);
PAINT GREEN (750 3125);
DISPLAY INVISIBLE (750 3125);
FORCEPROP 2 LAST CDS_LIB standard
J 0
(425 3250);
DISPLAY INVISIBLE (425 3250);
FORCEADD UNIVERSAL_POWER..1
(-3700 2875);
FORCEPROP 3 LASTPIN (-3700 2825) SIG_NAME P1V2_AUX\g
J 0
(-3690 2835);
DISPLAY 0.659574 (-3690 2835);
PAINT MONO (-3690 2835);
DISPLAY INVISIBLE (-3690 2835);
FORCEPROP 1 LAST HDL_POWER P1V2_AUX
J 1
(-3700 2925);
DISPLAY 0.702128 (-3700 2925);
PAINT GREEN (-3700 2925);
FORCEPROP 1 LAST PATH I8
J 0
(-3650 2900);
DISPLAY 0.872340 (-3650 2900);
PAINT AQUA (-3650 2900);
DISPLAY INVISIBLE (-3650 2900);
FORCEPROP 2 LAST CDS_LIB logical_power
J 0
(-3700 2875);
DISPLAY INVISIBLE (-3700 2875);
FORCEADD OFFPAGE..3
(425 3300);
FORCEPROP 2 LAST $XR0 12 
J 0
(639 3300);
DISPLAY 0.638298 (639 3300);
PAINT MONO (639 3300);
FORCEPROP 2 LAST PATH I80
J 0
(650 3350);
DISPLAY 1.021277 (650 3350);
DISPLAY INVISIBLE (650 3350);
FORCEPROP 1 LAST COMMENT_BODY TRUE
J 0
(375 3200);
DISPLAY 0.872340 (375 3200);
PAINT PEACH (375 3200);
DISPLAY INVISIBLE (375 3200);
FORCEPROP 1 LAST OFFPAGE TRUE
J 0
(750 3175);
DISPLAY 0.872340 (750 3175);
PAINT GREEN (750 3175);
DISPLAY INVISIBLE (750 3175);
FORCEPROP 2 LAST CDS_LIB standard
J 0
(425 3300);
DISPLAY INVISIBLE (425 3300);
FORCEADD OFFPAGE..3
(425 3350);
FORCEPROP 2 LAST $XR0 12 
J 0
(639 3350);
DISPLAY 0.638298 (639 3350);
PAINT MONO (639 3350);
FORCEPROP 2 LAST PATH I81
J 0
(650 3400);
DISPLAY 1.021277 (650 3400);
DISPLAY INVISIBLE (650 3400);
FORCEPROP 1 LAST COMMENT_BODY TRUE
J 0
(375 3250);
DISPLAY 0.872340 (375 3250);
PAINT PEACH (375 3250);
DISPLAY INVISIBLE (375 3250);
FORCEPROP 1 LAST OFFPAGE TRUE
J 0
(750 3225);
DISPLAY 0.872340 (750 3225);
PAINT GREEN (750 3225);
DISPLAY INVISIBLE (750 3225);
FORCEPROP 2 LAST CDS_LIB standard
J 0
(425 3350);
DISPLAY INVISIBLE (425 3350);
FORCEADD OFFPAGE..3
(425 3400);
FORCEPROP 2 LAST $XR0 12 
J 0
(639 3400);
DISPLAY 0.638298 (639 3400);
PAINT MONO (639 3400);
FORCEPROP 2 LAST PATH I82
J 0
(650 3450);
DISPLAY 1.021277 (650 3450);
DISPLAY INVISIBLE (650 3450);
FORCEPROP 1 LAST COMMENT_BODY TRUE
J 0
(375 3300);
DISPLAY 0.872340 (375 3300);
PAINT PEACH (375 3300);
DISPLAY INVISIBLE (375 3300);
FORCEPROP 1 LAST OFFPAGE TRUE
J 0
(750 3275);
DISPLAY 0.872340 (750 3275);
PAINT GREEN (750 3275);
DISPLAY INVISIBLE (750 3275);
FORCEPROP 2 LAST CDS_LIB standard
J 0
(425 3400);
DISPLAY INVISIBLE (425 3400);
FORCEADD OFFPAGE..4
(425 3450);
FORCEPROP 2 LAST $XR1 20 
J 0
(701 3450);
DISPLAY 0.638298 (701 3450);
PAINT MONO (701 3450);
FORCEPROP 2 LAST $XR0 12 
J 0
(611 3450);
DISPLAY 0.638298 (611 3450);
PAINT MONO (611 3450);
FORCEPROP 2 LAST PATH I83
J 0
(675 3500);
DISPLAY 1.021277 (675 3500);
DISPLAY INVISIBLE (675 3500);
FORCEPROP 1 LAST COMMENT_BODY TRUE
J 0
(400 3350);
DISPLAY 1.574468 (400 3350);
PAINT PEACH (400 3350);
DISPLAY INVISIBLE (400 3350);
FORCEPROP 1 LAST OFFPAGE TRUE
J 0
(750 3325);
DISPLAY 1.574468 (750 3325);
PAINT GREEN (750 3325);
DISPLAY INVISIBLE (750 3325);
FORCEPROP 2 LAST CDS_LIB standard
J 0
(425 3450);
DISPLAY INVISIBLE (425 3450);
FORCEADD OFFPAGE..4
(425 3500);
FORCEPROP 2 LAST $XR1 20 
J 0
(701 3500);
DISPLAY 0.638298 (701 3500);
PAINT MONO (701 3500);
FORCEPROP 2 LAST $XR0 12 
J 0
(611 3500);
DISPLAY 0.638298 (611 3500);
PAINT MONO (611 3500);
FORCEPROP 2 LAST PATH I84
J 0
(675 3550);
DISPLAY 1.021277 (675 3550);
DISPLAY INVISIBLE (675 3550);
FORCEPROP 1 LAST COMMENT_BODY TRUE
J 0
(400 3400);
DISPLAY 1.574468 (400 3400);
PAINT PEACH (400 3400);
DISPLAY INVISIBLE (400 3400);
FORCEPROP 1 LAST OFFPAGE TRUE
J 0
(750 3375);
DISPLAY 1.574468 (750 3375);
PAINT GREEN (750 3375);
DISPLAY INVISIBLE (750 3375);
FORCEPROP 2 LAST CDS_LIB standard
J 0
(425 3500);
DISPLAY INVISIBLE (425 3500);
FORCEADD Q_CAP..1
(800 2650);
FORCEPROP 1 LAST PACK_TYPE 0402
J 0
(875 2500);
DISPLAY 0.510638 (875 2500);
PAINT SKYBLUE (875 2500);
FORCEPROP 1 LAST VOLTAGE 25V
J 0
(875 2650);
DISPLAY 0.510638 (875 2650);
PAINT SKYBLUE (875 2650);
FORCEPROP 1 LAST VALUE 0.1UF
J 0
(875 2700);
DISPLAY 0.510638 (875 2700);
PAINT SKYBLUE (875 2700);
FORCEPROP 1 LAST PART_NUMBER CH4104K1B00
J 0
(875 2450);
DISPLAY 0.510638 (875 2450);
PAINT WHITE (875 2450);
FORCEPROP 1 LAST TOLERANCE 10%
J 0
(875 2600);
DISPLAY 0.510638 (875 2600);
PAINT SKYBLUE (875 2600);
FORCEPROP 1 LAST MATERIAL X7R
J 0
(875 2550);
DISPLAY 0.510638 (875 2550);
PAINT SKYBLUE (875 2550);
FORCEPROP 1 LAST PATH I85
J 0
(850 2800);
DISPLAY 0.978723 (850 2800);
PAINT WHITE (850 2800);
DISPLAY INVISIBLE (850 2800);
FORCEPROP 2 LAST SEC_TYPE 0402
J 0
(850 2850);
DISPLAY 0.680851 (850 2850);
DISPLAY INVISIBLE (850 2850);
FORCEPROP 2 LAST CDS_LIB pure_quanta
J 0
(800 2650);
DISPLAY INVISIBLE (800 2650);
FORCEPROP 1 LAST LOCATION C10
J 0
(875 2750);
DISPLAY 0.702128 (875 2750);
PAINT YELLOW (875 2750);
FORCEPROP 1 LASTPIN (800 2750) $PN 1
J 0
(810 2730);
DISPLAY 0.808511 (810 2730);
PAINT WHITE (810 2730);
FORCEPROP 1 LASTPIN (800 2550) $PN 2
J 0
(810 2530);
DISPLAY 0.808511 (810 2530);
PAINT WHITE (810 2530);
FORCEPROP 2 LAST SEC 1
J 0
(850 2850);
DISPLAY 0.680851 (850 2850);
PAINT MONO (850 2850);
DISPLAY INVISIBLE (850 2850);
FORCEADD OFFPAGE..4
(425 3650);
FORCEPROP 2 LAST $XR0 12 
J 0
(611 3650);
DISPLAY 0.638298 (611 3650);
PAINT MONO (611 3650);
FORCEPROP 2 LAST PATH I86
J 0
(625 3700);
DISPLAY 1.021277 (625 3700);
DISPLAY INVISIBLE (625 3700);
FORCEPROP 1 LAST COMMENT_BODY TRUE
J 0
(400 3550);
DISPLAY 1.574468 (400 3550);
PAINT PEACH (400 3550);
DISPLAY INVISIBLE (400 3550);
FORCEPROP 1 LAST OFFPAGE TRUE
J 0
(750 3525);
DISPLAY 1.574468 (750 3525);
PAINT GREEN (750 3525);
DISPLAY INVISIBLE (750 3525);
FORCEPROP 2 LAST CDS_LIB standard
J 0
(425 3650);
DISPLAY INVISIBLE (425 3650);
FORCEADD OFFPAGE..4
(425 3700);
FORCEPROP 2 LAST $XR0 12 
J 0
(611 3700);
DISPLAY 0.638298 (611 3700);
PAINT MONO (611 3700);
FORCEPROP 2 LAST PATH I87
J 0
(625 3750);
DISPLAY 1.021277 (625 3750);
DISPLAY INVISIBLE (625 3750);
FORCEPROP 1 LAST COMMENT_BODY TRUE
J 0
(400 3600);
DISPLAY 1.574468 (400 3600);
PAINT PEACH (400 3600);
DISPLAY INVISIBLE (400 3600);
FORCEPROP 1 LAST OFFPAGE TRUE
J 0
(750 3575);
DISPLAY 1.574468 (750 3575);
PAINT GREEN (750 3575);
DISPLAY INVISIBLE (750 3575);
FORCEPROP 2 LAST CDS_LIB standard
J 0
(425 3700);
DISPLAY INVISIBLE (425 3700);
FORCEADD OFFPAGE..3
(850 4600);
FORCEPROP 2 LAST $XR0 12 
J 0
(1064 4600);
DISPLAY 0.638298 (1064 4600);
PAINT MONO (1064 4600);
FORCEPROP 2 LAST PATH I88
J 0
(1075 4650);
DISPLAY 1.021277 (1075 4650);
DISPLAY INVISIBLE (1075 4650);
FORCEPROP 1 LAST COMMENT_BODY TRUE
J 0
(800 4500);
DISPLAY 0.872340 (800 4500);
PAINT PEACH (800 4500);
DISPLAY INVISIBLE (800 4500);
FORCEPROP 1 LAST OFFPAGE TRUE
J 0
(1175 4475);
DISPLAY 0.872340 (1175 4475);
PAINT GREEN (1175 4475);
DISPLAY INVISIBLE (1175 4475);
FORCEPROP 2 LAST CDS_LIB standard
J 0
(850 4600);
DISPLAY INVISIBLE (850 4600);
FORCEADD Q_RES..1
(2075 -1150);
FORCEPROP 1 LAST MATERIAL CHIP
J 0
(2400 -1125);
DISPLAY 0.510638 (2400 -1125);
PAINT SKYBLUE (2400 -1125);
FORCEPROP 1 LAST VALUE 60.4
J 2
(2375 -1125);
DISPLAY 0.510638 (2375 -1125);
PAINT SKYBLUE (2375 -1125);
FORCEPROP 1 LAST PART_NUMBER CS06042FB03
J 0
(2125 -1025);
DISPLAY 0.510638 (2125 -1025);
PAINT WHITE (2125 -1025);
DISPLAY INVISIBLE (2125 -1025);
FORCEPROP 1 LAST PACK_TYPE 0402LF
J 0
(2325 -1300);
DISPLAY 0.510638 (2325 -1300);
PAINT SKYBLUE (2325 -1300);
DISPLAY INVISIBLE (2325 -1300);
FORCEPROP 1 LAST WATTAGE 1/16W
J 2
(2050 -1300);
DISPLAY 0.510638 (2050 -1300);
PAINT SKYBLUE (2050 -1300);
DISPLAY INVISIBLE (2050 -1300);
FORCEPROP 1 LAST PATH I89
J 0
(2025 -1000);
DISPLAY 0.978723 (2025 -1000);
PAINT WHITE (2025 -1000);
DISPLAY INVISIBLE (2025 -1000);
FORCEPROP 1 LAST TOLERANCE 1%
J 0
(2075 -1250);
DISPLAY 0.510638 (2075 -1250);
PAINT SKYBLUE (2075 -1250);
DISPLAY INVISIBLE (2075 -1250);
FORCEPROP 2 LAST SEC_TYPE 0402LF
J 0
(2025 -950);
DISPLAY 0.680851 (2025 -950);
DISPLAY INVISIBLE (2025 -950);
FORCEPROP 2 LAST CDS_LIB pure_quanta
J 0
(2075 -1150);
DISPLAY INVISIBLE (2075 -1150);
FORCEPROP 1 LAST LOCATION R8
J 0
(1875 -1150);
DISPLAY 0.702128 (1875 -1150);
PAINT YELLOW (1875 -1150);
FORCEPROP 1 LASTPIN (1975 -1150) $PN 1
J 0
(1987 -1138);
DISPLAY 0.808511 (1987 -1138);
PAINT WHITE (1987 -1138);
FORCEPROP 1 LASTPIN (2175 -1150) $PN 2
J 0
(2137 -1138);
DISPLAY 0.808511 (2137 -1138);
PAINT WHITE (2137 -1138);
FORCEPROP 2 LAST SEC 1
J 0
(2025 -950);
DISPLAY 0.680851 (2025 -950);
PAINT MONO (2025 -950);
DISPLAY INVISIBLE (2025 -950);
FORCEADD OFFPAGE..3
R 2
(-2925 3800);
FORCEPROP 2 LAST $XR1 20 
J 0
(-3264 3800);
DISPLAY 0.638298 (-3264 3800);
PAINT MONO (-3264 3800);
FORCEPROP 2 LAST $XR0 12 
J 0
(-3174 3800);
DISPLAY 0.638298 (-3174 3800);
PAINT MONO (-3174 3800);
FORCEPROP 2 LAST PATH I9
J 0
(-3150 3850);
DISPLAY 1.021277 (-3150 3850);
DISPLAY INVISIBLE (-3150 3850);
FORCEPROP 1 LAST COMMENT_BODY TRUE
J 2
(-2875 3700);
DISPLAY 0.872340 (-2875 3700);
PAINT PEACH (-2875 3700);
DISPLAY INVISIBLE (-2875 3700);
FORCEPROP 1 LAST OFFPAGE TRUE
J 2
(-3250 3675);
DISPLAY 0.872340 (-3250 3675);
PAINT GREEN (-3250 3675);
DISPLAY INVISIBLE (-3250 3675);
FORCEPROP 2 LAST CDS_LIB standard
J 0
(-2925 3800);
DISPLAY INVISIBLE (-2925 3800);
FORCEADD Q_RES..1
(2075 -950);
FORCEPROP 1 LAST MATERIAL CHIP
J 0
(2400 -925);
DISPLAY 0.510638 (2400 -925);
PAINT SKYBLUE (2400 -925);
FORCEPROP 1 LAST VALUE 60.4
J 2
(2375 -925);
DISPLAY 0.510638 (2375 -925);
PAINT SKYBLUE (2375 -925);
FORCEPROP 1 LAST PART_NUMBER CS06042FB03
J 0
(2125 -825);
DISPLAY 0.510638 (2125 -825);
PAINT WHITE (2125 -825);
FORCEPROP 1 LAST PACK_TYPE 0402LF
J 0
(2325 -1100);
DISPLAY 0.510638 (2325 -1100);
PAINT SKYBLUE (2325 -1100);
DISPLAY INVISIBLE (2325 -1100);
FORCEPROP 1 LAST WATTAGE 1/16W
J 2
(2050 -1100);
DISPLAY 0.510638 (2050 -1100);
PAINT SKYBLUE (2050 -1100);
DISPLAY INVISIBLE (2050 -1100);
FORCEPROP 1 LAST PATH I90
J 0
(2025 -800);
DISPLAY 0.978723 (2025 -800);
PAINT WHITE (2025 -800);
DISPLAY INVISIBLE (2025 -800);
FORCEPROP 1 LAST TOLERANCE 1%
J 0
(2075 -1050);
DISPLAY 0.510638 (2075 -1050);
PAINT SKYBLUE (2075 -1050);
DISPLAY INVISIBLE (2075 -1050);
FORCEPROP 2 LAST SEC_TYPE 0402LF
J 0
(2025 -750);
DISPLAY 0.680851 (2025 -750);
DISPLAY INVISIBLE (2025 -750);
FORCEPROP 2 LAST CDS_LIB pure_quanta
J 0
(2075 -950);
DISPLAY INVISIBLE (2075 -950);
FORCEPROP 1 LAST LOCATION R7
J 0
(1875 -950);
DISPLAY 0.702128 (1875 -950);
PAINT YELLOW (1875 -950);
FORCEPROP 1 LASTPIN (1975 -950) $PN 1
J 0
(1987 -938);
DISPLAY 0.808511 (1987 -938);
PAINT WHITE (1987 -938);
FORCEPROP 1 LASTPIN (2175 -950) $PN 2
J 0
(2137 -938);
DISPLAY 0.808511 (2137 -938);
PAINT WHITE (2137 -938);
FORCEPROP 2 LAST SEC 1
J 0
(2025 -750);
DISPLAY 0.680851 (2025 -750);
PAINT MONO (2025 -750);
DISPLAY INVISIBLE (2025 -750);
FORCEADD UNIVERSAL_POWER..1
(1150 275);
FORCEPROP 3 LASTPIN (1150 225) SIG_NAME P0V6_DDR_VREF_AUX\g
J 0
(1160 235);
DISPLAY 0.659574 (1160 235);
PAINT MONO (1160 235);
DISPLAY INVISIBLE (1160 235);
FORCEPROP 1 LAST HDL_POWER P0V6_DDR_VREF_AUX
J 1
(1225 325);
DISPLAY 0.702128 (1225 325);
PAINT GREEN (1225 325);
FORCEPROP 1 LAST PATH I91
J 0
(1200 300);
DISPLAY 0.872340 (1200 300);
PAINT AQUA (1200 300);
DISPLAY INVISIBLE (1200 300);
FORCEPROP 2 LAST CDS_LIB logical_power
J 0
(1150 275);
DISPLAY INVISIBLE (1150 275);
FORCEADD OFFPAGE..2
R 2
(2375 175);
FORCEPROP 2 LAST $XR1 20 
J 0
(2061 175);
DISPLAY 0.638298 (2061 175);
PAINT MONO (2061 175);
FORCEPROP 2 LAST $XR0 12 
J 0
(2151 175);
DISPLAY 0.638298 (2151 175);
PAINT MONO (2151 175);
FORCEPROP 2 LAST PATH I92
J 0
(2200 225);
DISPLAY 1.021277 (2200 225);
DISPLAY INVISIBLE (2200 225);
FORCEPROP 1 LAST COMMENT_BODY TRUE
J 2
(2420 80);
DISPLAY 0.872340 (2420 80);
PAINT PEACH (2420 80);
DISPLAY INVISIBLE (2420 80);
FORCEPROP 1 LAST OFFPAGE TRUE
J 2
(2050 50);
DISPLAY 0.872340 (2050 50);
PAINT GREEN (2050 50);
DISPLAY INVISIBLE (2050 50);
FORCEPROP 2 LAST CDS_LIB standard
J 0
(2375 175);
DISPLAY INVISIBLE (2375 175);
FORCEADD UNIVERSAL_GND..1
(1475 2450);
FORCEPROP 3 LASTPIN (1475 2500) SIG_NAME GND\g
J 0
(1485 2510);
DISPLAY 0.659574 (1485 2510);
PAINT MONO (1485 2510);
DISPLAY INVISIBLE (1485 2510);
FORCEPROP 1 LAST PATH I93
J 0
(1550 2450);
DISPLAY 0.872340 (1550 2450);
PAINT AQUA (1550 2450);
DISPLAY INVISIBLE (1550 2450);
FORCEPROP 1 LAST HDL_POWER GND
J 1
(1500 2375);
DISPLAY 0.702128 (1500 2375);
PAINT GREEN (1500 2375);
DISPLAY INVISIBLE (1500 2375);
FORCEPROP 2 LAST CDS_LIB logical_power
J 0
(1475 2450);
DISPLAY INVISIBLE (1475 2450);
FORCEADD UNIVERSAL_GND..1
(2075 2450);
FORCEPROP 3 LASTPIN (2075 2500) SIG_NAME GND\g
J 0
(2085 2510);
DISPLAY 0.659574 (2085 2510);
PAINT MONO (2085 2510);
DISPLAY INVISIBLE (2085 2510);
FORCEPROP 1 LAST PATH I94
J 0
(2150 2450);
DISPLAY 0.872340 (2150 2450);
PAINT AQUA (2150 2450);
DISPLAY INVISIBLE (2150 2450);
FORCEPROP 1 LAST HDL_POWER GND
J 1
(2100 2375);
DISPLAY 0.702128 (2100 2375);
PAINT GREEN (2100 2375);
DISPLAY INVISIBLE (2100 2375);
FORCEPROP 2 LAST CDS_LIB logical_power
J 0
(2075 2450);
DISPLAY INVISIBLE (2075 2450);
FORCEADD OFFPAGE..2
R 2
(2375 500);
FORCEPROP 2 LAST $XR1 20 
J 0
(2061 500);
DISPLAY 0.638298 (2061 500);
PAINT MONO (2061 500);
FORCEPROP 2 LAST $XR0 12 
J 0
(2151 500);
DISPLAY 0.638298 (2151 500);
PAINT MONO (2151 500);
FORCEPROP 2 LAST PATH I95
J 0
(2200 550);
DISPLAY 1.021277 (2200 550);
DISPLAY INVISIBLE (2200 550);
FORCEPROP 1 LAST COMMENT_BODY TRUE
J 2
(2420 405);
DISPLAY 0.872340 (2420 405);
PAINT PEACH (2420 405);
DISPLAY INVISIBLE (2420 405);
FORCEPROP 1 LAST OFFPAGE TRUE
J 2
(2050 375);
DISPLAY 0.872340 (2050 375);
PAINT GREEN (2050 375);
DISPLAY INVISIBLE (2050 375);
FORCEPROP 2 LAST CDS_LIB standard
J 0
(2375 500);
DISPLAY INVISIBLE (2375 500);
FORCEADD OFFPAGE..2
R 2
(2375 675);
FORCEPROP 2 LAST $XR1 20 
J 0
(2061 675);
DISPLAY 0.638298 (2061 675);
PAINT MONO (2061 675);
FORCEPROP 2 LAST $XR0 12 
J 0
(2151 675);
DISPLAY 0.638298 (2151 675);
PAINT MONO (2151 675);
FORCEPROP 2 LAST PATH I96
J 0
(2200 725);
DISPLAY 1.021277 (2200 725);
DISPLAY INVISIBLE (2200 725);
FORCEPROP 1 LAST COMMENT_BODY TRUE
J 2
(2420 580);
DISPLAY 0.872340 (2420 580);
PAINT PEACH (2420 580);
DISPLAY INVISIBLE (2420 580);
FORCEPROP 1 LAST OFFPAGE TRUE
J 2
(2050 550);
DISPLAY 0.872340 (2050 550);
PAINT GREEN (2050 550);
DISPLAY INVISIBLE (2050 550);
FORCEPROP 2 LAST CDS_LIB standard
J 0
(2375 675);
DISPLAY INVISIBLE (2375 675);
FORCEADD OFFPAGE..2
R 2
(2375 825);
FORCEPROP 2 LAST $XR1 20 
J 0
(2061 825);
DISPLAY 0.638298 (2061 825);
PAINT MONO (2061 825);
FORCEPROP 2 LAST $XR0 12 
J 0
(2151 825);
DISPLAY 0.638298 (2151 825);
PAINT MONO (2151 825);
FORCEPROP 2 LAST PATH I97
J 0
(2200 875);
DISPLAY 1.021277 (2200 875);
DISPLAY INVISIBLE (2200 875);
FORCEPROP 1 LAST COMMENT_BODY TRUE
J 2
(2420 730);
DISPLAY 0.872340 (2420 730);
PAINT PEACH (2420 730);
DISPLAY INVISIBLE (2420 730);
FORCEPROP 1 LAST OFFPAGE TRUE
J 2
(2050 700);
DISPLAY 0.872340 (2050 700);
PAINT GREEN (2050 700);
DISPLAY INVISIBLE (2050 700);
FORCEPROP 2 LAST CDS_LIB standard
J 0
(2375 825);
DISPLAY INVISIBLE (2375 825);
FORCEADD OFFPAGE..2
R 2
(2375 975);
FORCEPROP 2 LAST $XR1 20 
J 0
(2061 975);
DISPLAY 0.638298 (2061 975);
PAINT MONO (2061 975);
FORCEPROP 2 LAST $XR0 12 
J 0
(2151 975);
DISPLAY 0.638298 (2151 975);
PAINT MONO (2151 975);
FORCEPROP 2 LAST PATH I98
J 0
(2200 1025);
DISPLAY 1.021277 (2200 1025);
DISPLAY INVISIBLE (2200 1025);
FORCEPROP 1 LAST COMMENT_BODY TRUE
J 2
(2420 880);
DISPLAY 0.872340 (2420 880);
PAINT PEACH (2420 880);
DISPLAY INVISIBLE (2420 880);
FORCEPROP 1 LAST OFFPAGE TRUE
J 2
(2050 850);
DISPLAY 0.872340 (2050 850);
PAINT GREEN (2050 850);
DISPLAY INVISIBLE (2050 850);
FORCEPROP 2 LAST CDS_LIB standard
J 0
(2375 975);
DISPLAY INVISIBLE (2375 975);
FORCEADD OFFPAGE..2
R 2
(2375 1125);
FORCEPROP 2 LAST $XR0 12 
J 0
(2151 1125);
DISPLAY 0.638298 (2151 1125);
PAINT MONO (2151 1125);
FORCEPROP 2 LAST $XR1 20 
J 0
(2061 1125);
DISPLAY 0.638298 (2061 1125);
PAINT MONO (2061 1125);
FORCEPROP 2 LAST PATH I99
J 0
(2200 1175);
DISPLAY 1.021277 (2200 1175);
DISPLAY INVISIBLE (2200 1175);
FORCEPROP 1 LAST COMMENT_BODY TRUE
J 2
(2420 1030);
DISPLAY 0.872340 (2420 1030);
PAINT PEACH (2420 1030);
DISPLAY INVISIBLE (2420 1030);
FORCEPROP 1 LAST OFFPAGE TRUE
J 2
(2050 1000);
DISPLAY 0.872340 (2050 1000);
PAINT GREEN (2050 1000);
DISPLAY INVISIBLE (2050 1000);
FORCEPROP 2 LAST CDS_LIB standard
J 0
(2375 1125);
DISPLAY INVISIBLE (2375 1125);
FORCEADD QUANTA_TITLE_BLOCK_C..1
(5425 -1625);
FORCEPROP 0 LAST CDS_CON_LAST_MODIFIED Fri Aug 25 17:25:39 2023
J 0
(3540 -1610);
DISPLAY INVISIBLE (3540 -1610);
FORCEPROP 2 LAST Q_DEPT 
J 1
(1662 -1576);
DISPLAY 1.957447 (1662 -1576);
PAINT GREEN (1662 -1576);
FORCEPROP 1 LAST CUSTOM_TXT_CDS <CON_LAST_MODIFIED>
J 0
(3540 -1610);
DISPLAY 0.978723 (3540 -1610);
FORCEPROP 2 LAST CUSTOM_TXT_CDS <XR_PAGE_TITLE>
J 0
(-2465 3625);
DISPLAY 0.638298 (-2465 3625);
PAINT PINK (-2465 3625);
DISPLAY INVISIBLE (-2465 3625);
FORCEPROP 1 LAST CUSTOM_TXT_CDS <NAME_2>
J 0
(2250 -1575);
FORCEPROP 1 LAST CUSTOM_TXT_CDS <NAME_1>
J 0
(2250 -1450);
FORCEPROP 1 LAST CUSTOM_TXT_CDS <Q_NUMBER>
J 0
(4022 -1522);
DISPLAY 1.212766 (4022 -1522);
FORCEPROP 1 LAST CUSTOM_TXT_CDS <Q_PROJ>
J 0
(3043 -1523);
DISPLAY 1.212766 (3043 -1523);
FORCEPROP 1 LAST CUSTOM_TXT_CDS <Q_REV>
J 0
(5241 -1522);
DISPLAY 1.212766 (5241 -1522);
FORCEPROP 1 LAST CUSTOM_TXT_CDS <CON_PAGE_NUM> OF <CON_TOTAL_PAGES>
J 0
(4979 -1607);
DISPLAY 0.978723 (4979 -1607);
FORCEPROP 1 LAST Q_TITLE BMC DDR4 SDRAM
J 0
(-3941 -1599);
DISPLAY 2.446809 (-3941 -1599);
PAINT GREEN (-3941 -1599);
FORCEPROP 1 LAST COMMENT_BODY TRUE
J 0
(5437 -1638);
DISPLAY 0.978723 (5437 -1638);
PAINT PEACH (5437 -1638);
DISPLAY INVISIBLE (5437 -1638);
FORCEPROP 1 LAST CDS_LMAN_SYM_OUTLINE -9475,6775,100,-125
J 0
(5425 -1625);
DISPLAY 0.468085 (5425 -1625);
PAINT GREEN (5425 -1625);
DISPLAY INVISIBLE (5425 -1625);
FORCEPROP 2 LAST CDS_LIB pure_quanta
J 0
(5425 -1625);
DISPLAY INVISIBLE (5425 -1625);
FORCEPROP 2 LAST PAGE_BORDER TRUE
J 0
(-2465 3625);
DISPLAY 0.638298 (-2465 3625);
PAINT PINK (-2465 3625);
DISPLAY INVISIBLE (-2465 3625);
FORCEPROP 2 LAST CDS_XR_PAGE_TITLE CR-20 : @SCM_LIB.SCM(SCH_1):PAGE20
J 0
(-2465 3625);
DISPLAY 0.638298 (-2465 3625);
PAINT PINK (-2465 3625);
DISPLAY INVISIBLE (-2465 3625);
FORCEADD DNS..1
(4300 425);
PAINT RED (4300 425);
FORCEPROP 1 LAST COMMENT_BODY TRUE
R 1
J 0
(4375 200);
DISPLAY 0.872340 (4375 200);
PAINT PEACH (4375 200);
DISPLAY INVISIBLE (4375 200);
FORCEPROP 2 LAST CDS_LIB mstr_misc
J 0
(4300 425);
DISPLAY INVISIBLE (4300 425);
FORCEADD DNS..1
(3650 400);
PAINT RED (3650 400);
FORCEPROP 2 LAST CDS_LIB mstr_misc
J 0
(3650 400);
DISPLAY INVISIBLE (3650 400);
FORCEPROP 1 LAST COMMENT_BODY TRUE
R 1
J 0
(3725 175);
DISPLAY 0.872340 (3725 175);
PAINT PEACH (3725 175);
DISPLAY INVISIBLE (3725 175);
FORCEADD DNS..1
(450 425);
PAINT RED (450 425);
FORCEPROP 1 LAST COMMENT_BODY TRUE
R 1
J 0
(525 200);
DISPLAY 0.872340 (525 200);
PAINT PEACH (525 200);
DISPLAY INVISIBLE (525 200);
FORCEPROP 2 LAST CDS_LIB mstr_misc
J 0
(450 425);
DISPLAY INVISIBLE (450 425);
FORCEADD DNS..1
(-2400 -825);
PAINT RED (-2400 -825);
FORCEPROP 1 LAST COMMENT_BODY TRUE
R 1
J 0
(-2325 -1050);
DISPLAY 0.872340 (-2325 -1050);
PAINT PEACH (-2325 -1050);
DISPLAY INVISIBLE (-2325 -1050);
FORCEPROP 2 LAST CDS_LIB mstr_misc
J 0
(-2400 -825);
DISPLAY INVISIBLE (-2400 -825);
FORCEADD DNS..1
(3700 -725);
PAINT RED (3700 -725);
FORCEPROP 1 LAST COMMENT_BODY TRUE
R 1
J 0
(3775 -950);
DISPLAY 0.872340 (3775 -950);
PAINT PEACH (3775 -950);
DISPLAY INVISIBLE (3775 -950);
FORCEPROP 2 LAST CDS_LIB mstr_misc
J 0
(3700 -725);
DISPLAY INVISIBLE (3700 -725);
WIRE 17 -1 (100 3825)(100 3775);
WIRE 17 -1 (100 3825)(100 3875);
WIRE 17 -1 (100 3875)(100 3925);
WIRE 17 -1 (100 3925)(100 3975);
WIRE 17 -1 (100 3975)(100 4025);
WIRE 17 -1 (100 4025)(100 4075);
WIRE 17 -1 (100 4075)(100 4125);
WIRE 17 -1 (100 4125)(100 4175);
WIRE 17 -1 (100 4175)(100 4225);
WIRE 17 -1 (100 4225)(100 4275);
WIRE 17 -1 (100 4275)(100 4325);
WIRE 17 -1 (100 4325)(100 4375);
WIRE 17 -1 (100 4375)(100 4425);
WIRE 17 -1 (100 4425)(100 4475);
WIRE 17 -1 (100 4475)(100 4525);
WIRE 17 -1 (100 4525)(100 4600);
WIRE 17 -1 (100 4600)(800 4600);
FORCEPROP 2 LAST SIG_NAME M_BMC_DDR4_DQ[15:0]
J 0
(165 4610);
DISPLAY 0.808511 (165 4610);
WIRE 17 -1 (-2075 3325)(-2075 3375);
WIRE 17 -1 (-2075 3275)(-2075 3325);
WIRE 17 -1 (-2075 3375)(-2075 3425);
WIRE 17 -1 (-2075 3425)(-2075 3475);
WIRE 17 -1 (-2075 3225)(-2075 3275);
WIRE 17 -1 (-2075 3175)(-2075 3225);
WIRE 17 -1 (-2075 3475)(-2075 3525);
WIRE 17 -1 (-2075 3525)(-2075 3575);
WIRE 17 -1 (-2075 3125)(-2075 3175);
WIRE 17 -1 (-2075 3575)(-2075 3625);
WIRE 17 -1 (-2075 3625)(-2075 3675);
WIRE 17 -1 (-2075 3675)(-2075 3725);
WIRE 17 -1 (-2075 3725)(-2075 3775);
WIRE 17 -1 (-2075 3775)(-2075 3800);
WIRE 17 -1 (-2075 3800)(-2875 3800);
FORCEPROP 2 LAST SIG_NAME M_BMC_DDR4_MA[13:0]
J 0
(-2860 3810);
DISPLAY 0.808511 (-2860 3810);
WIRE 17 -1 (2625 3400)(2625 3250);
WIRE 17 -1 (2625 3550)(2625 3400);
WIRE 17 -1 (2625 3250)(2625 3100);
WIRE 17 -1 (2625 3100)(2625 2950);
WIRE 17 -1 (2625 3700)(2625 3550);
WIRE 17 -1 (2625 3850)(2625 3700);
WIRE 17 -1 (2625 2950)(2625 2800);
WIRE 17 -1 (2625 3850)(2625 4000);
WIRE 17 -1 (2625 4000)(2625 4150);
WIRE 17 -1 (2625 4150)(2625 4300);
WIRE 17 -1 (2625 4300)(2625 4450);
WIRE 17 -1 (2625 4450)(2625 4600);
WIRE 17 -1 (2625 4600)(2625 4750);
WIRE 17 -1 (2625 4750)(2625 4825);
WIRE 17 -1 (1675 4825)(2625 4825);
FORCEPROP 2 LAST SIG_NAME M_BMC_DDR4_MA[13:0]
J 0
(1765 4835);
DISPLAY 0.808511 (1765 4835);
WIRE 16 -1 (-3700 2750)(-3700 2825);
WIRE 16 -1 (-3700 2750)(-3475 2750);
WIRE 16 -1 (-3700 2750)(-3700 2575);
WIRE 16 -1 (-250 625)(-250 725);
WIRE 16 -1 (-250 625)(475 625);
WIRE 16 -1 (-250 450)(-250 625);
WIRE 16 -1 (-3050 1525)(-3050 1575);
WIRE 16 -1 (-2775 1525)(-3050 1525);
WIRE 16 -1 (-3050 1400)(-3050 1525);
WIRE 16 -1 (4725 4750)(4725 4800);
WIRE 16 -1 (4725 4750)(5175 4750);
WIRE 16 -1 (4725 4650)(4725 4750);
WIRE 16 -1 (4775 2075)(4775 1925);
WIRE 16 -1 (4175 -750)(4175 -525);
WIRE 16 -1 (3800 -750)(4175 -750);
WIRE 16 -1 (1150 2800)(1150 2825);
WIRE 16 -1 (800 2800)(1150 2800);
WIRE 16 -1 (1150 125)(1150 225);
WIRE 16 -1 (550 125)(1150 125);
WIRE 16 -1 (2075 2675)(2075 2500);
WIRE 16 -1 (1475 2575)(1475 2500);
WIRE 16 -1 (1475 2575)(1750 2575);
WIRE 16 -1 (1400 2575)(1475 2575);
WIRE 16 -1 (800 2550)(800 2500);
WIRE 16 -1 (-275 1375)(-275 1700);
WIRE 16 -1 (350 -375)(350 -425);
WIRE 16 -1 (350 -375)(550 -375);
WIRE 16 -1 (150 -375)(350 -375);
WIRE 16 -1 (-3600 2200)(-3600 2100);
WIRE 16 -1 (-3700 2200)(-3600 2200);
WIRE 16 -1 (-3600 2200)(-3475 2200);
WIRE 16 -1 (-2550 1750)(-2550 1775);
WIRE 16 -1 (-2925 1075)(-2925 1000);
WIRE 16 -1 (-2925 1075)(-3050 1075);
WIRE 16 -1 (-2925 1075)(-2775 1075);
WIRE 16 -1 (5175 4500)(5175 4475);
WIRE 16 -1 (5025 4175)(5025 4150);
WIRE 16 -1 (4950 3875)(4950 3850);
WIRE 16 -1 (4875 3550)(4875 3525);
WIRE 16 -1 (-1950 -450)(-1950 -550);
WIRE 16 -1 (-2250 -450)(-1950 -450);
WIRE 16 -1 (-2025 -1050)(-2025 -1150);
WIRE 16 -1 (-2325 -1050)(-2025 -1050);
WIRE 16 -1 (4975 975)(4975 900);
WIRE 16 -1 (3225 2475)(3225 2700);
WIRE 16 -1 (4975 225)(4975 150);
WIRE 16 -1 (3275 425)(3275 0);
WIRE 16 -1 (3275 575)(3275 425);
WIRE 16 -1 (3550 425)(3275 425);
WIRE 16 -1 (4000 -1050)(4000 -1250);
WIRE 16 -1 (3800 -1050)(4000 -1050);
WIRE 16 -1 (-550 1700)(-275 1700);
WIRE 16 -1 (-275 1750)(-275 1700);
WIRE 16 -1 (-550 1750)(-275 1750);
WIRE 16 -1 (-275 1800)(-275 1750);
WIRE 16 -1 (-550 1800)(-275 1800);
WIRE 16 -1 (-275 1850)(-275 1800);
WIRE 16 -1 (-550 1850)(-275 1850);
WIRE 16 -1 (-275 1900)(-275 1850);
WIRE 16 -1 (-550 1900)(-275 1900);
WIRE 16 -1 (-275 1950)(-275 1900);
WIRE 16 -1 (-550 1950)(-275 1950);
WIRE 16 -1 (-275 2000)(-275 1950);
WIRE 16 -1 (-550 2000)(-275 2000);
WIRE 16 -1 (-275 2050)(-275 2000);
WIRE 16 -1 (-550 2050)(-275 2050);
WIRE 16 -1 (-275 2100)(-275 2050);
WIRE 16 -1 (-550 2100)(-275 2100);
WIRE 16 -1 (-275 2150)(-275 2100);
WIRE 16 -1 (-550 2150)(-275 2150);
WIRE 16 -1 (-275 2200)(-275 2150);
WIRE 16 -1 (-550 2200)(-275 2200);
WIRE 16 -1 (-275 2250)(-275 2200);
WIRE 16 -1 (-550 2250)(-275 2250);
WIRE 16 -1 (-275 2250)(-275 2350);
WIRE 16 -1 (-550 2350)(-275 2350);
WIRE 16 -1 (-275 2400)(-275 2350);
WIRE 16 -1 (-550 2400)(-275 2400);
WIRE 16 -1 (-275 2450)(-275 2400);
WIRE 16 -1 (-550 2450)(-275 2450);
WIRE 16 -1 (-275 2450)(-275 2550);
WIRE 16 -1 (-550 2550)(-275 2550);
WIRE 16 -1 (-275 2600)(-275 2550);
WIRE 16 -1 (-550 2600)(-275 2600);
WIRE 16 -1 (-275 2700)(-275 2600);
WIRE 16 -1 (-550 2700)(-275 2700);
WIRE 16 -1 (-3200 -450)(-2450 -450);
FORCEPROP 2 LAST SIG_NAME M_BMC_DDR4_ZQU
J 0
(-3160 -440);
DISPLAY 0.808511 (-3160 -440);
WIRE 16 -1 (-2325 -850)(-1300 -850);
FORCEPROP 2 LAST SIG_NAME M_BMC_DDR4_MBG1
J 0
(-1985 -840);
DISPLAY 0.808511 (-1985 -840);
WIRE 16 3135 (-800 675)(-800 -1350);
WIRE 16 3135 (-800 675)(-3700 675);
WIRE 16 3135 (-3700 -1350)(-800 -1350);
WIRE 16 3135 (-3700 -1350)(-3700 675);
WIRE 16 -1 (-250 -175)(-250 -375);
WIRE 16 -1 (-250 -375)(150 -375);
WIRE 16 -1 (150 -175)(150 -375);
WIRE 16 -1 (550 -375)(550 -175);
WIRE 16 -1 (-250 125)(-250 25);
WIRE 16 -1 (-250 250)(-250 125);
WIRE 16 -1 (-250 125)(150 125);
WIRE 16 -1 (150 125)(150 25);
WIRE 16 -1 (150 125)(475 125);
WIRE 16 -1 (475 300)(475 125);
WIRE 16 -1 (475 125)(550 125);
WIRE 16 -1 (550 125)(550 25);
WIRE 16 -1 (3350 -750)(3600 -750);
WIRE 16 -1 (2175 -1150)(2600 -1150);
WIRE 16 -1 (3600 -1050)(3350 -1050);
WIRE 16 -1 (3350 -1050)(3350 -750);
WIRE 16 -1 (3350 -1050)(2600 -1050);
FORCEPROP 2 LAST SIG_NAME M_BMC_DDR4_MCLK_C
J 0
(2640 -1025);
DISPLAY 0.808511 (2640 -1025);
WIRE 16 -1 (2600 -1050)(2600 -1150);
WIRE 16 -1 (2600 -950)(2600 -1050);
WIRE 16 -1 (2175 -950)(2600 -950);
WIRE 16 -1 (2425 175)(4225 175);
FORCEPROP 2 LAST SIG_NAME M_BMC_DDR4_ALERT_N
J 0
(2465 185);
DISPLAY 0.808511 (2465 185);
WIRE 16 -1 (4025 500)(2425 500);
FORCEPROP 2 LAST SIG_NAME M_BMC_DDR4_MBG1
J 0
(2465 510);
DISPLAY 0.808511 (2465 510);
WIRE 16 -1 (4025 425)(4225 425);
WIRE 16 -1 (3750 425)(4025 425);
WIRE 16 -1 (4025 425)(4025 500);
WIRE 16 -1 (4025 675)(2425 675);
FORCEPROP 2 LAST SIG_NAME M_BMC_DDR4_MCKE
J 0
(2465 685);
DISPLAY 0.808511 (2465 685);
WIRE 16 -1 (4025 575)(4225 575);
WIRE 16 -1 (3750 575)(4025 575);
WIRE 16 -1 (4025 575)(4025 675);
WIRE 16 -1 (4025 825)(2425 825);
FORCEPROP 2 LAST SIG_NAME M_BMC_DDR4_MODT
J 0
(2465 835);
DISPLAY 0.808511 (2465 835);
WIRE 16 -1 (4025 725)(4225 725);
WIRE 16 -1 (3750 725)(4025 725);
WIRE 16 -1 (4025 725)(4025 825);
WIRE 16 -1 (4025 975)(2425 975);
FORCEPROP 2 LAST SIG_NAME M_BMC_DDR4_MBA1
J 0
(2465 985);
DISPLAY 0.808511 (2465 985);
WIRE 16 -1 (4025 875)(4225 875);
WIRE 16 -1 (3750 875)(4025 875);
WIRE 16 -1 (4025 875)(4025 975);
WIRE 16 -1 (4025 1125)(2425 1125);
FORCEPROP 2 LAST SIG_NAME M_BMC_DDR4_MBA0
J 0
(2465 1135);
DISPLAY 0.808511 (2465 1135);
WIRE 16 -1 (4025 1025)(4225 1025);
WIRE 16 -1 (3750 1025)(4025 1025);
WIRE 16 -1 (4025 1025)(4025 1125);
WIRE 16 -1 (4025 1275)(2425 1275);
FORCEPROP 2 LAST SIG_NAME M_BMC_DDR4_MBG0
J 0
(2465 1285);
DISPLAY 0.808511 (2465 1285);
WIRE 16 -1 (4025 1175)(4225 1175);
WIRE 16 -1 (3750 1175)(4025 1175);
WIRE 16 -1 (4025 1175)(4025 1275);
WIRE 16 -1 (4025 1425)(2425 1425);
FORCEPROP 2 LAST SIG_NAME M_BMC_DDR4_MACT_N
J 0
(2465 1435);
DISPLAY 0.808511 (2465 1435);
WIRE 16 -1 (4025 1325)(4225 1325);
WIRE 16 -1 (3750 1325)(4025 1325);
WIRE 16 -1 (4025 1325)(4025 1425);
WIRE 16 -1 (4025 1575)(2425 1575);
FORCEPROP 2 LAST SIG_NAME M_BMC_DDR4_MCS_N
J 0
(2465 1585);
DISPLAY 0.808511 (2465 1585);
WIRE 16 -1 (4025 1475)(4225 1475);
WIRE 16 -1 (3750 1475)(4025 1475);
WIRE 16 -1 (4025 1475)(4025 1575);
WIRE 16 -1 (4025 1875)(2425 1875);
FORCEPROP 2 LAST SIG_NAME M_BMC_DDR4_MCAS_N
J 0
(2465 1885);
DISPLAY 0.808511 (2465 1885);
WIRE 16 -1 (4025 1775)(4225 1775);
WIRE 16 -1 (3750 1775)(4025 1775);
WIRE 16 -1 (4025 1775)(4025 1875);
WIRE 16 -1 (4025 2025)(2425 2025);
WIRE 16 -1 (4025 1925)(4225 1925);
WIRE 16 -1 (3750 1925)(4025 1925);
WIRE 16 -1 (4025 1925)(4025 2025);
WIRE 16 -1 (3975 3675)(2725 3675);
WIRE 16 -1 (3975 3600)(4175 3600);
WIRE 16 -1 (3700 3600)(3975 3600);
WIRE 16 -1 (3975 3600)(3975 3675);
WIRE 16 -1 (3975 3825)(2725 3825);
WIRE 16 -1 (3975 3750)(4175 3750);
WIRE 16 -1 (3700 3750)(3975 3750);
WIRE 16 -1 (3975 3750)(3975 3825);
WIRE 16 -1 (3500 4650)(3225 4650);
WIRE 16 -1 (3500 4500)(3225 4500);
WIRE 16 -1 (3225 4650)(3225 4500);
WIRE 16 -1 (3225 4500)(3225 4350);
WIRE 16 -1 (3500 4350)(3225 4350);
WIRE 16 -1 (3225 4350)(3225 4200);
WIRE 16 -1 (3500 4200)(3225 4200);
WIRE 16 -1 (3500 4050)(3225 4050);
WIRE 16 -1 (3225 4200)(3225 4050);
WIRE 16 -1 (3225 4050)(3225 3900);
WIRE 16 -1 (3500 3900)(3225 3900);
WIRE 16 -1 (3225 3900)(3225 3750);
WIRE 16 -1 (3500 3750)(3225 3750);
WIRE 16 -1 (3225 3750)(3225 3600);
WIRE 16 -1 (3500 3600)(3225 3600);
WIRE 16 -1 (3500 3450)(3225 3450);
WIRE 16 -1 (3225 3600)(3225 3450);
WIRE 16 -1 (3225 3450)(3225 3300);
WIRE 16 -1 (3500 3300)(3225 3300);
WIRE 16 -1 (3225 3300)(3225 3150);
WIRE 16 -1 (3500 3150)(3225 3150);
WIRE 16 -1 (3500 3000)(3225 3000);
WIRE 16 -1 (3225 3150)(3225 3000);
WIRE 16 -1 (3225 2850)(3225 3000);
WIRE 16 -1 (3500 2850)(3225 2850);
WIRE 16 -1 (3225 2700)(3225 2850);
WIRE 16 -1 (3500 2700)(3225 2700);
WIRE 16 -1 (3975 3975)(2725 3975);
WIRE 16 -1 (3975 3900)(4175 3900);
WIRE 16 -1 (3700 3900)(3975 3900);
WIRE 16 -1 (3975 3900)(3975 3975);
WIRE 16 -1 (3975 4125)(2725 4125);
WIRE 16 -1 (3975 4050)(3975 4125);
WIRE 16 -1 (3975 4050)(4175 4050);
WIRE 16 -1 (3700 4050)(3975 4050);
WIRE 16 -1 (3975 3525)(2725 3525);
WIRE 16 -1 (3975 3450)(4175 3450);
WIRE 16 -1 (3700 3450)(3975 3450);
WIRE 16 -1 (3975 3450)(3975 3525);
WIRE 16 -1 (4725 2700)(4375 2700);
WIRE 16 -1 (4725 2850)(4375 2850);
WIRE 16 -1 (4725 2850)(4725 2700);
WIRE 16 -1 (4725 3000)(4375 3000);
WIRE 16 -1 (4725 3000)(4725 2850);
WIRE 16 -1 (4725 3150)(4725 3000);
WIRE 16 -1 (4725 3150)(4375 3150);
WIRE 16 -1 (4725 3300)(4375 3300);
WIRE 16 -1 (4725 3300)(4725 3150);
WIRE 16 -1 (4725 3450)(4375 3450);
WIRE 16 -1 (4725 3450)(4725 3300);
WIRE 16 -1 (4725 3600)(4375 3600);
WIRE 16 -1 (4725 3600)(4725 3450);
WIRE 16 -1 (4875 3825)(4875 3750);
WIRE 16 -1 (4725 3750)(4375 3750);
WIRE 16 -1 (4725 3750)(4725 3600);
WIRE 16 -1 (4725 3825)(4725 3750);
WIRE 16 -1 (4725 3825)(4875 3825);
WIRE 16 -1 (4725 3900)(4375 3900);
WIRE 16 -1 (4725 3900)(4725 3825);
WIRE 16 -1 (4950 4125)(4950 4075);
WIRE 16 -1 (4725 4050)(4375 4050);
WIRE 16 -1 (4725 4050)(4725 3900);
WIRE 16 -1 (4725 4125)(4725 4050);
WIRE 16 -1 (4725 4125)(4950 4125);
WIRE 16 -1 (4725 4200)(4375 4200);
WIRE 16 -1 (4725 4200)(4725 4125);
WIRE 16 -1 (5025 4425)(5025 4375);
WIRE 16 -1 (4725 4350)(4375 4350);
WIRE 16 -1 (4725 4350)(4725 4200);
WIRE 16 -1 (4725 4425)(4725 4350);
WIRE 16 -1 (4725 4425)(5025 4425);
WIRE 16 -1 (4725 4500)(4375 4500);
WIRE 16 -1 (4725 4500)(4725 4425);
WIRE 16 -1 (4725 4650)(4725 4500);
WIRE 16 -1 (4375 4650)(4725 4650);
WIRE 16 -1 (5175 4750)(5175 4700);
WIRE 16 -1 (4425 1925)(4775 1925);
WIRE 16 -1 (4775 1775)(4425 1775);
WIRE 16 -1 (4775 1925)(4775 1775);
WIRE 16 -1 (4775 1625)(4425 1625);
WIRE 16 -1 (4775 1775)(4775 1625);
WIRE 16 -1 (4775 1475)(4425 1475);
WIRE 16 -1 (4775 1625)(4775 1475);
WIRE 16 -1 (4975 1250)(4975 1175);
WIRE 16 -1 (4775 1325)(4425 1325);
WIRE 16 -1 (4775 1475)(4775 1325);
WIRE 16 -1 (4775 1325)(4775 1250);
WIRE 16 -1 (4775 1250)(4975 1250);
WIRE 16 -1 (4775 1175)(4425 1175);
WIRE 16 -1 (4775 1250)(4775 1175);
WIRE 16 -1 (4775 1025)(4425 1025);
WIRE 16 -1 (4775 1025)(4775 1175);
WIRE 16 -1 (4775 875)(4425 875);
WIRE 16 -1 (4775 1025)(4775 875);
WIRE 16 -1 (4775 725)(4425 725);
WIRE 16 -1 (4775 875)(4775 725);
WIRE 16 -1 (4975 500)(4975 425);
WIRE 16 -1 (4775 575)(4425 575);
WIRE 16 -1 (4775 725)(4775 575);
WIRE 16 -1 (4775 575)(4775 500);
WIRE 16 -1 (4775 500)(4975 500);
WIRE 16 -1 (4775 425)(4425 425);
WIRE 16 -1 (4775 500)(4775 425);
WIRE 16 -1 (4775 425)(4775 175);
WIRE 16 -1 (4425 175)(4775 175);
WIRE 16 -1 (-2650 -1050)(-2525 -1050);
WIRE 16 -1 (-2650 -850)(-2525 -850);
WIRE 16 -1 (-3200 -850)(-2650 -850);
FORCEPROP 2 LAST SIG_NAME M_BMC_DDR4_BG1
J 0
(-3185 -840);
DISPLAY 0.808511 (-3185 -840);
WIRE 16 -1 (-2650 -850)(-2650 -1050);
WIRE 16 -1 (-550 2800)(800 2800);
WIRE 16 -1 (800 2800)(800 2750);
WIRE 16 -1 (-550 2950)(1400 2950);
FORCEPROP 2 LAST SIG_NAME PD_M_BMC_DDR4_PAR
J 2
(315 2960);
DISPLAY 0.808511 (315 2960);
WIRE 16 -1 (1400 2950)(1400 2875);
WIRE 16 -1 (-550 3000)(1750 3000);
FORCEPROP 2 LAST SIG_NAME PD_M_BMC_DDR4_TEN
J 2
(315 3010);
DISPLAY 0.808511 (315 3010);
WIRE 16 -1 (1750 3000)(1750 2875);
WIRE 16 -1 (375 3050)(-550 3050);
FORCEPROP 2 LAST SIG_NAME M_BMC_DDR4_ALERT_N
J 2
(315 3060);
DISPLAY 0.808511 (315 3060);
WIRE 16 -1 (-550 3100)(2075 3100);
FORCEPROP 2 LAST SIG_NAME PD_M_BMC_DDR4_ZQ
J 2
(315 3110);
DISPLAY 0.808511 (315 3110);
WIRE 16 -1 (2075 3100)(2075 2875);
WIRE 16 -1 (375 3250)(-550 3250);
FORCEPROP 2 LAST SIG_NAME M_BMC_DDR4_DQS0_N
J 2
(315 3260);
DISPLAY 0.808511 (315 3260);
WIRE 16 -1 (375 3300)(-550 3300);
FORCEPROP 2 LAST SIG_NAME M_BMC_DDR4_DQS0_P
J 2
(315 3310);
DISPLAY 0.808511 (315 3310);
WIRE 16 -1 (375 3350)(-550 3350);
FORCEPROP 2 LAST SIG_NAME M_BMC_DDR4_DQS1_N
J 2
(315 3360);
DISPLAY 0.808511 (315 3360);
WIRE 16 -1 (375 3400)(-550 3400);
FORCEPROP 2 LAST SIG_NAME M_BMC_DDR4_DQS1_P
J 2
(315 3410);
DISPLAY 0.808511 (315 3410);
WIRE 16 -1 (375 3450)(-550 3450);
FORCEPROP 2 LAST SIG_NAME M_BMC_DDR4_MCLK_DN
J 2
(315 3460);
DISPLAY 0.808511 (315 3460);
WIRE 16 -1 (375 3500)(-550 3500);
FORCEPROP 2 LAST SIG_NAME M_BMC_DDR4_MCLK_DP
J 2
(315 3510);
DISPLAY 0.808511 (315 3510);
WIRE 16 -1 (-1600 3750)(-1975 3750);
WIRE 16 -1 (-1600 3700)(-1975 3700);
WIRE 16 -1 (-1600 3650)(-1975 3650);
WIRE 16 -1 (-1600 3600)(-1975 3600);
WIRE 16 -1 (-1600 3500)(-1975 3500);
WIRE 16 -1 (-1600 3550)(-1975 3550);
WIRE 16 -1 (-1600 2900)(-2500 2900);
FORCEPROP 2 LAST SIG_NAME M_BMC_DDR4_RST_N
J 0
(-2435 2910);
DISPLAY 0.808511 (-2435 2910);
WIRE 16 -1 (-3475 2750)(-3475 2575);
WIRE 16 -1 (-3475 2750)(-3275 2750);
WIRE 16 -1 (-3275 2750)(-3275 2575);
WIRE 16 -1 (-3275 2750)(-3075 2750);
WIRE 16 -1 (-3075 2750)(-3075 2575);
WIRE 16 -1 (-3075 2750)(-2875 2750);
WIRE 16 -1 (-2875 2750)(-2875 2575);
WIRE 16 -1 (-2875 2750)(-2650 2750);
WIRE 16 -1 (-2650 2750)(-2650 2575);
WIRE 16 -1 (-2400 2750)(-2650 2750);
WIRE 16 -1 (-2400 2750)(-2400 2575);
WIRE 16 -1 (-2400 2750)(-1875 2750);
WIRE 16 -1 (-1875 2750)(-1600 2750);
WIRE 16 -1 (-1875 2700)(-1875 2750);
WIRE 16 -1 (-1875 2700)(-1600 2700);
WIRE 16 -1 (-1875 2650)(-1875 2700);
WIRE 16 -1 (-1875 2650)(-1600 2650);
WIRE 16 -1 (-1875 2600)(-1875 2650);
WIRE 16 -1 (-1875 2600)(-1600 2600);
WIRE 16 -1 (-1875 2550)(-1600 2550);
WIRE 16 -1 (-1875 2550)(-1875 2600);
WIRE 16 -1 (-1875 2500)(-1875 2550);
WIRE 16 -1 (-1875 2500)(-1600 2500);
WIRE 16 -1 (-1875 2450)(-1875 2500);
WIRE 16 -1 (-1875 2450)(-1600 2450);
WIRE 16 -1 (-1875 2400)(-1875 2450);
WIRE 16 -1 (-1875 2400)(-1600 2400);
WIRE 16 -1 (-1875 2350)(-1875 2400);
WIRE 16 -1 (-1875 2350)(-1600 2350);
WIRE 16 -1 (-1875 2300)(-1875 2350);
WIRE 16 -1 (-1875 2300)(-1600 2300);
WIRE 16 -1 (-2550 2125)(-2550 2050);
WIRE 16 -1 (-1875 2250)(-1875 2300);
WIRE 16 -1 (-1875 2250)(-1600 2250);
WIRE 16 -1 (-1875 2200)(-1875 2250);
WIRE 16 -1 (-1875 2200)(-1600 2200);
WIRE 16 -1 (-2350 2125)(-2350 2050);
WIRE 16 -1 (-2550 2125)(-2350 2125);
WIRE 16 -1 (-2125 2125)(-2125 2050);
WIRE 16 -1 (-2350 2125)(-2125 2125);
WIRE 16 -1 (-1875 2150)(-1875 2200);
WIRE 16 -1 (-1875 2150)(-1600 2150);
WIRE 16 -1 (-1875 2125)(-1875 2150);
WIRE 16 -1 (-2125 2125)(-1875 2125);
WIRE 16 -1 (-1875 2100)(-1875 2125);
WIRE 16 -1 (-1875 2100)(-1600 2100);
WIRE 16 -1 (-1875 2050)(-1875 2100);
WIRE 16 -1 (-1875 2050)(-1600 2050);
WIRE 16 -1 (-1875 2000)(-1600 2000);
WIRE 16 -1 (-1875 2000)(-1875 2050);
WIRE 16 -1 (-1875 1950)(-1875 2000);
WIRE 16 -1 (-1875 1950)(-1600 1950);
WIRE 16 -1 (-1875 1900)(-1875 1950);
WIRE 16 -1 (-1875 1900)(-1600 1900);
WIRE 16 -1 (-1875 1850)(-1875 1900);
WIRE 16 -1 (-1875 1850)(-1600 1850);
WIRE 16 -1 (-1875 1800)(-1875 1850);
WIRE 16 -1 (-1875 1800)(-1600 1800);
WIRE 16 -1 (-2400 2375)(-2400 2200);
WIRE 16 -1 (-2650 2375)(-2650 2200);
WIRE 16 -1 (-2400 2200)(-2650 2200);
WIRE 16 -1 (-2875 2375)(-2875 2200);
WIRE 16 -1 (-2875 2200)(-2650 2200);
WIRE 16 -1 (-3075 2375)(-3075 2200);
WIRE 16 -1 (-3075 2200)(-2875 2200);
WIRE 16 -1 (-3275 2200)(-3075 2200);
WIRE 16 -1 (-3275 2375)(-3275 2200);
WIRE 16 -1 (-3475 2375)(-3475 2200);
WIRE 16 -1 (-3475 2200)(-3275 2200);
WIRE 16 -1 (-3700 2375)(-3700 2200);
WIRE 16 -1 (-2550 1850)(-2550 1775);
WIRE 16 -1 (-2550 1775)(-2350 1775);
WIRE 16 -1 (-2350 1850)(-2350 1775);
WIRE 16 -1 (-2350 1775)(-2125 1775);
WIRE 16 -1 (-2125 1775)(-2125 1850);
WIRE 16 -1 (-1875 1750)(-1600 1750);
WIRE 16 -1 (-1875 1700)(-1600 1700);
WIRE 16 -1 (-1875 1750)(-1875 1700);
WIRE 16 -1 (-1875 1700)(-1875 1525);
WIRE 16 -1 (-2775 1400)(-2775 1525);
WIRE 16 -1 (-1875 1525)(-2775 1525);
WIRE 16 -1 (400 2500)(-550 2500);
FORCEPROP 2 LAST SIG_NAME M_BMC_DDR4_ZQU
J 0
(-210 2510);
DISPLAY 0.808511 (-210 2510);
WIRE 16 -1 (400 2300)(-550 2300);
FORCEPROP 2 LAST SIG_NAME M_BMC_DDR4_BG1
J 0
(-210 2310);
DISPLAY 0.808511 (-210 2310);
WIRE 16 -1 (-1600 4400)(-2500 4400);
FORCEPROP 2 LAST SIG_NAME M_BMC_DDR4_MCAS_N
J 0
(-2460 4410);
DISPLAY 0.808511 (-2460 4410);
WIRE 16 -1 (-1600 4350)(-2500 4350);
FORCEPROP 2 LAST SIG_NAME M_BMC_DDR4_MWE_N
J 0
(-2460 4360);
DISPLAY 0.808511 (-2460 4360);
WIRE 16 -1 (-1600 4300)(-2500 4300);
FORCEPROP 2 LAST SIG_NAME M_BMC_DDR4_MCKE
J 0
(-2460 4310);
DISPLAY 0.808511 (-2460 4310);
WIRE 16 -1 (-1600 4200)(-2500 4200);
FORCEPROP 2 LAST SIG_NAME M_BMC_DDR4_MACT_N
J 0
(-2460 4210);
DISPLAY 0.808511 (-2460 4210);
WIRE 16 -1 (-2900 3950)(-1600 3950);
FORCEPROP 2 LAST SIG_NAME M_BMC_DDR4_MBG0
J 0
(-2860 3960);
DISPLAY 0.808511 (-2860 3960);
WIRE 16 -1 (-2900 3900)(-1600 3900);
FORCEPROP 2 LAST SIG_NAME M_BMC_DDR4_MBA0
J 0
(-2860 3910);
DISPLAY 0.808511 (-2860 3910);
WIRE 16 -1 (-2900 3850)(-1600 3850);
FORCEPROP 2 LAST SIG_NAME M_BMC_DDR4_MBA1
J 0
(-2860 3860);
DISPLAY 0.808511 (-2860 3860);
WIRE 16 -1 (475 625)(475 500);
WIRE 16 -1 (3550 575)(3275 575);
WIRE 16 -1 (3275 725)(3275 575);
WIRE 16 -1 (3550 725)(3275 725);
WIRE 16 -1 (3275 875)(3275 725);
WIRE 16 -1 (3550 875)(3275 875);
WIRE 16 -1 (3275 1025)(3275 875);
WIRE 16 -1 (3550 1025)(3275 1025);
WIRE 16 -1 (3275 1175)(3275 1025);
WIRE 16 -1 (3550 1175)(3275 1175);
WIRE 16 -1 (3275 1325)(3275 1175);
WIRE 16 -1 (3550 1325)(3275 1325);
WIRE 16 -1 (3275 1475)(3275 1325);
WIRE 16 -1 (3550 1475)(3275 1475);
WIRE 16 -1 (3275 1625)(3275 1475);
WIRE 16 -1 (3550 1625)(3275 1625);
WIRE 16 -1 (3275 1775)(3275 1625);
WIRE 16 -1 (3550 1775)(3275 1775);
WIRE 16 -1 (3275 1925)(3275 1775);
WIRE 16 -1 (3550 1925)(3275 1925);
WIRE 16 -1 (4025 1725)(2425 1725);
FORCEPROP 2 LAST SIG_NAME M_BMC_DDR4_MRAS_N
J 0
(2465 1735);
DISPLAY 0.808511 (2465 1735);
WIRE 16 -1 (4025 1625)(4225 1625);
WIRE 16 -1 (3750 1625)(4025 1625);
WIRE 16 -1 (4025 1625)(4025 1725);
WIRE 16 -1 (3975 2775)(2725 2775);
WIRE 16 -1 (3975 2700)(3700 2700);
WIRE 16 -1 (4175 2700)(3975 2700);
WIRE 16 -1 (3975 2700)(3975 2775);
WIRE 16 -1 (3975 2925)(2725 2925);
WIRE 16 -1 (3975 2850)(3700 2850);
WIRE 16 -1 (4175 2850)(3975 2850);
WIRE 16 -1 (3975 2850)(3975 2925);
WIRE 16 -1 (3975 3075)(2725 3075);
WIRE 16 -1 (3975 3000)(4175 3000);
WIRE 16 -1 (3700 3000)(3975 3000);
WIRE 16 -1 (3975 3000)(3975 3075);
WIRE 16 -1 (3975 3225)(2725 3225);
WIRE 16 -1 (3975 3150)(4175 3150);
WIRE 16 -1 (3700 3150)(3975 3150);
WIRE 16 -1 (3975 3150)(3975 3225);
WIRE 16 -1 (-2775 1075)(-2775 1200);
WIRE 16 -1 (-3050 1075)(-3050 1200);
WIRE 16 -1 (1400 2675)(1400 2575);
WIRE 16 -1 (1750 2575)(1750 2675);
WIRE 16 -1 (1975 -950)(1150 -950);
FORCEPROP 2 LAST SIG_NAME M_BMC_DDR4_MCLK_DN
J 0
(1140 -940);
DISPLAY 0.808511 (1140 -940);
WIRE 16 -1 (1975 -1150)(1150 -1150);
FORCEPROP 2 LAST SIG_NAME M_BMC_DDR4_MCLK_DP
J 0
(1140 -1140);
DISPLAY 0.808511 (1140 -1140);
WIRE 16 -1 (3975 4725)(2725 4725);
WIRE 16 -1 (3975 4650)(4175 4650);
WIRE 16 -1 (3700 4650)(3975 4650);
WIRE 16 -1 (3975 4650)(3975 4725);
WIRE 16 -1 (3975 4575)(2725 4575);
WIRE 16 -1 (3975 4500)(4175 4500);
WIRE 16 -1 (3700 4500)(3975 4500);
WIRE 16 -1 (3975 4500)(3975 4575);
WIRE 16 -1 (3975 4425)(2725 4425);
WIRE 16 -1 (3975 4350)(4175 4350);
WIRE 16 -1 (3700 4350)(3975 4350);
WIRE 16 -1 (3975 4350)(3975 4425);
WIRE 16 -1 (3975 4275)(2725 4275);
WIRE 16 -1 (3975 4200)(4175 4200);
WIRE 16 -1 (3700 4200)(3975 4200);
WIRE 16 -1 (3975 4200)(3975 4275);
WIRE 16 -1 (3975 3375)(2725 3375);
WIRE 16 -1 (3975 3300)(4175 3300);
WIRE 16 -1 (3700 3300)(3975 3300);
WIRE 16 -1 (3975 3300)(3975 3375);
WIRE 16 -1 (-1600 4250)(-2500 4250);
FORCEPROP 2 LAST SIG_NAME M_BMC_DDR4_MODT
J 0
(-2460 4260);
DISPLAY 0.808511 (-2460 4260);
WIRE 16 -1 (-1600 4450)(-2500 4450);
FORCEPROP 2 LAST SIG_NAME M_BMC_DDR4_MRAS_N
J 0
(-2460 4460);
DISPLAY 0.808511 (-2460 4460);
WIRE 16 -1 (-1600 4500)(-2500 4500);
FORCEPROP 2 LAST SIG_NAME M_BMC_DDR4_MCS_N
J 0
(-2460 4510);
DISPLAY 0.808511 (-2460 4510);
WIRE 16 -1 (375 3650)(-550 3650);
FORCEPROP 2 LAST SIG_NAME M_BMC_DDR4_MDM0
J 2
(315 3660);
DISPLAY 0.808511 (315 3660);
WIRE 16 -1 (375 3700)(-550 3700);
FORCEPROP 2 LAST SIG_NAME M_BMC_DDR4_MDM1
J 2
(315 3710);
DISPLAY 0.808511 (315 3710);
WIRE 16 -1 (-1600 3100)(-1975 3100);
WIRE 16 -1 (-1600 3250)(-1975 3250);
WIRE 16 -1 (-1600 3450)(-1975 3450);
WIRE 16 -1 (-1600 3200)(-1975 3200);
WIRE 16 -1 (-1600 3150)(-1975 3150);
WIRE 16 -1 (-1600 3400)(-1975 3400);
WIRE 16 -1 (-1600 3350)(-1975 3350);
WIRE 16 -1 (-1600 3300)(-1975 3300);
WIRE 16 -1 (0 4500)(-550 4500);
WIRE 16 -1 (0 4450)(-550 4450);
WIRE 16 -1 (0 4400)(-550 4400);
WIRE 16 -1 (0 4350)(-550 4350);
WIRE 16 -1 (0 4300)(-550 4300);
WIRE 16 -1 (0 4250)(-550 4250);
WIRE 16 -1 (0 4200)(-550 4200);
WIRE 16 -1 (0 4150)(-550 4150);
WIRE 16 -1 (0 4100)(-550 4100);
WIRE 16 -1 (0 4050)(-550 4050);
WIRE 16 -1 (0 4000)(-550 4000);
WIRE 16 -1 (0 3950)(-550 3950);
WIRE 16 -1 (0 3900)(-550 3900);
WIRE 16 -1 (0 3850)(-550 3850);
WIRE 16 -1 (0 3800)(-550 3800);
WIRE 16 -1 (0 3750)(-550 3750);
DOT 1 (4775 1775);
DOT 1 (4775 1475);
DOT 1 (4025 425);
DOT 1 (-2650 -850);
DOT 1 (-2775 1525);
DOT 1 (3275 1775);
DOT 1 (3975 3150);
DOT 1 (3275 725);
DOT 1 (550 125);
DOT 1 (475 125);
DOT 1 (4025 575);
DOT 1 (3275 1325);
DOT 1 (-1875 2750);
DOT 1 (4775 1325);
DOT 1 (3275 1625);
DOT 1 (-2550 1775);
DOT 1 (-2350 1775);
DOT 1 (-2925 1075);
DOT 1 (-3050 1525);
DOT 1 (-1875 2050);
DOT 1 (-1875 2100);
DOT 1 (-1875 2125);
DOT 1 (-2125 2125);
DOT 1 (-2400 2750);
DOT 1 (-2350 2125);
DOT 1 (-1875 2700);
DOT 1 (-3075 2750);
DOT 1 (-275 1850);
DOT 1 (1475 2575);
DOT 1 (3225 3000);
DOT 1 (3225 3900);
DOT 1 (3275 575);
DOT 1 (4725 4650);
DOT 1 (4725 4750);
DOT 1 (3975 4650);
DOT 1 (4725 4050);
DOT 1 (4725 3750);
DOT 1 (4725 4500);
DOT 1 (4725 4200);
DOT 1 (4725 4425);
DOT 1 (4725 3825);
DOT 1 (4725 2850);
DOT 1 (3975 4500);
DOT 1 (3975 4350);
DOT 1 (3975 4200);
DOT 1 (3225 4350);
DOT 1 (3225 4500);
DOT 1 (3225 4200);
DOT 1 (3225 4050);
DOT 1 (3225 3600);
DOT 1 (3975 2850);
DOT 1 (3975 2700);
DOT 1 (3225 3300);
DOT 1 (3225 3450);
DOT 1 (3225 3150);
DOT 1 (3225 2850);
DOT 1 (3225 2700);
DOT 1 (4775 1925);
DOT 1 (4775 1175);
DOT 1 (4775 1025);
DOT 1 (4775 725);
DOT 1 (4775 575);
DOT 1 (4775 500);
DOT 1 (4025 1925);
DOT 1 (4025 1625);
DOT 1 (3275 1475);
DOT 1 (3275 1175);
DOT 1 (3275 1025);
DOT 1 (3275 875);
DOT 1 (4775 425);
DOT 1 (3275 425);
DOT 1 (3350 -1050);
DOT 1 (800 2800);
DOT 1 (-275 2600);
DOT 1 (-1875 2650);
DOT 1 (-1875 2600);
DOT 1 (-1875 2500);
DOT 1 (-1875 2550);
DOT 1 (-2650 2750);
DOT 1 (-2875 2750);
DOT 1 (-275 2400);
DOT 1 (-275 2350);
DOT 1 (-275 2450);
DOT 1 (-275 2250);
DOT 1 (-275 2200);
DOT 1 (-275 2150);
DOT 1 (-275 2100);
DOT 1 (-275 2000);
DOT 1 (-275 1950);
DOT 1 (-275 1800);
DOT 1 (-275 1900);
DOT 1 (-275 1750);
DOT 1 (-275 1700);
DOT 1 (-250 625);
DOT 1 (150 125);
DOT 1 (350 -375);
DOT 1 (150 -375);
DOT 1 (-250 125);
DOT 1 (-1875 2450);
DOT 1 (-1875 2400);
DOT 1 (-1875 2350);
DOT 1 (-1875 2250);
DOT 1 (-1875 2300);
DOT 1 (-1875 2200);
DOT 1 (-1875 2000);
DOT 1 (-1875 1950);
DOT 1 (-1875 1900);
DOT 1 (-1875 1850);
DOT 1 (-1875 1700);
DOT 1 (-2875 2200);
DOT 1 (-3475 2750);
DOT 1 (-3700 2750);
DOT 1 (-3275 2200);
DOT 1 (-3475 2200);
DOT 1 (4725 4350);
DOT 1 (4725 3900);
DOT 1 (4725 3000);
DOT 1 (4725 3150);
DOT 1 (3225 3750);
DOT 1 (4725 3300);
DOT 1 (3975 4050);
DOT 1 (4725 4125);
DOT 1 (3975 3300);
DOT 1 (3975 3450);
DOT 1 (3975 3600);
DOT 1 (3975 3750);
DOT 1 (3975 3900);
DOT 1 (3975 3000);
DOT 1 (4725 3600);
DOT 1 (4725 3450);
DOT 1 (2600 -1050);
DOT 1 (4025 1775);
DOT 1 (4025 875);
DOT 1 (4025 1025);
DOT 1 (4025 1175);
DOT 1 (4025 1325);
DOT 1 (4775 875);
DOT 1 (-275 2050);
DOT 1 (-1875 2150);
DOT 1 (-3075 2200);
DOT 1 (-2650 2200);
DOT 1 (4775 1250);
DOT 1 (4025 1475);
DOT 1 (4775 1625);
DOT 1 (4025 725);
DOT 1 (-3600 2200);
DOT 1 (-3275 2750);
DOT 1 (-275 2550);
FORCENOTE
SINGLE/TWIN DIE SELECTION
(-3500 525) 0;
DISPLAY LEFT (-3500 525);
DISPLAY 1.595745 (-3500 525);
PAINT WHITE (-3500 525);
FORCENOTE
R3 = 240 OHM(1%) STUFF
(-3500 25) 0;
DISPLAY LEFT (-3500 25);
DISPLAY 1.021277 (-3500 25);
PAINT WHITE (-3500 25);
FORCENOTE
FOR SINGLE DIE PART:(DEFAULT)
(-3500 425) 0;
DISPLAY LEFT (-3500 425);
DISPLAY 1.021277 (-3500 425);
PAINT WHITE (-3500 425);
FORCENOTE
R2 UNSTUFF
(-3500 -125) 0;
DISPLAY LEFT (-3500 -125);
DISPLAY 1.021277 (-3500 -125);
PAINT WHITE (-3500 -125);
FORCENOTE
R1 STUFF
(-3500 -50) 0;
DISPLAY LEFT (-3500 -50);
DISPLAY 1.021277 (-3500 -50);
PAINT WHITE (-3500 -50);
FORCENOTE
FOR TWIN DIE PART:
(-3500 100) 0;
DISPLAY LEFT (-3500 100);
DISPLAY 1.021277 (-3500 100);
PAINT WHITE (-3500 100);
FORCENOTE
R2 STUFF
(-3500 200) 0;
DISPLAY LEFT (-3500 200);
DISPLAY 1.021277 (-3500 200);
PAINT WHITE (-3500 200);
FORCENOTE
R1 UNSTUFF
(-3500 275) 0;
DISPLAY LEFT (-3500 275);
DISPLAY 1.021277 (-3500 275);
PAINT WHITE (-3500 275);
FORCENOTE
R3 = 0 OHM STUFF
(-3500 350) 0;
DISPLAY LEFT (-3500 350);
DISPLAY 1.021277 (-3500 350);
PAINT WHITE (-3500 350);
FORCENOTE
R337 STUFF
(-3500 -200) 0;
DISPLAY LEFT (-3500 -200);
DISPLAY 1.021277 (-3500 -200);
PAINT WHITE (-3500 -200);
QUIT
